G04 ================== begin FILE IDENTIFICATION RECORD ==================*
G04 Layout Name:  D:/<user>/Wistron_project/16318-2/gbr/16318-2.brd*
G04 Film Name:    L7GND*
G04 File Format:  Gerber RS274X*
G04 File Origin:  Cadence Allegro 16.5-S056*
G04 Origin Date:  Mon Aug 07 11:09:50 2017*
G04 *
G04 Layer:  VIA CLASS/L7GND*
G04 Layer:  PIN/L7GND*
G04 Layer:  ETCH/L7GND*
G04 Layer:  DRAWING FORMAT/LAYER_PCB_STORY*
G04 Layer:  DRAWING FORMAT/LAYER_L7GND*
G04 *
G04 Offset:    (0.00 0.00)*
G04 Mirror:    No*
G04 Mode:      Negative*
G04 Rotation:  0*
G04 FullContactRelief:  No*
G04 UndefLineWidth:     6.00*
G04 ================== end FILE IDENTIFICATION RECORD ====================*
%FSLAX35Y35*MOIN*%
%IR0*IPPOS*OFA0.00000B0.00000*MIA0B0*SFA1.00000B1.00000*%
%AMMACRO12*
4,1,13,.02632,.01218,
.028035,.007425,
.028899,.002443,
.028884,-.002612,
.027991,-.007588,
.02632,-.01218,
.03005,-.01591,
.032356,-.01045,
.033679,-.004673,
.033979,.001247,
.033246,.007128,
.031504,.012793,
.03005,.01591,
.02632,.01218,
0.0*
4,1,13,.01218,-.02632,
.007425,-.028035,
.002443,-.028899,
-.002612,-.028884,
-.007588,-.027991,
-.01218,-.02632,
-.01591,-.03005,
-.01045,-.032356,
-.004673,-.033679,
.001247,-.033979,
.007128,-.033246,
.012793,-.031504,
.01591,-.03005,
.01218,-.02632,
0.0*
4,1,13,-.02632,-.01218,
-.028035,-.007425,
-.028899,-.002443,
-.028884,.002612,
-.027991,.007588,
-.02632,.01218,
-.03005,.01591,
-.032356,.01045,
-.033679,.004673,
-.033979,-.001247,
-.033246,-.007128,
-.031504,-.012793,
-.03005,-.01591,
-.02632,-.01218,
0.0*
4,1,13,-.01218,.02632,
-.007425,.028035,
-.002443,.028899,
.002612,.028884,
.007588,.027991,
.01218,.02632,
.01591,.03005,
.01045,.032356,
.004673,.033679,
-.001247,.033979,
-.007128,.033246,
-.012793,.031504,
-.01591,.03005,
-.01218,.02632,
0.0*
%
%ADD12MACRO12*%
%ADD26O,.072X.123*%
%ADD14C,.03*%
%ADD32C,.032*%
%ADD39C,.051*%
%ADD25C,.06*%
%ADD33C,.043*%
%ADD29C,.062*%
%ADD36C,.063*%
%ADD20C,.036*%
%ADD23C,.028*%
%ADD30C,.056*%
%ADD28C,.076*%
%ADD11C,.068*%
%AMMACRO19*
4,1,15,.00398,.00044,
.003999,.000208,
.004004,-.000025,
.003996,-.000258,
.00398,-.00044,
.00483,-.00129,
.004897,-.001007,
.004947,-.000721,
.004981,-.000432,
.004997,-.000141,
.004997,.000149,
.00498,.00044,
.004946,.000729,
.004895,.001015,
.00483,.00129,
.00398,.00044,
90.*
4,1,15,.00044,-.00398,
.000208,-.003999,
-.000025,-.004004,
-.000258,-.003996,
-.00044,-.00398,
-.00129,-.00483,
-.001007,-.004897,
-.000721,-.004947,
-.000432,-.004981,
-.000141,-.004997,
.000149,-.004997,
.00044,-.00498,
.000729,-.004946,
.001015,-.004895,
.00129,-.00483,
.00044,-.00398,
90.*
4,1,15,-.00398,-.00044,
-.003999,-.000208,
-.004004,.000025,
-.003996,.000258,
-.00398,.00044,
-.00483,.00129,
-.004897,.001007,
-.004947,.000721,
-.004981,.000432,
-.004997,.000141,
-.004997,-.000149,
-.00498,-.00044,
-.004946,-.000729,
-.004895,-.001015,
-.00483,-.00129,
-.00398,-.00044,
90.*
4,1,15,-.00044,.00398,
-.000208,.003999,
.000025,.004004,
.000258,.003996,
.00044,.00398,
.00129,.00483,
.001007,.004897,
.000721,.004947,
.000432,.004981,
.000141,.004997,
-.000149,.004997,
-.00044,.00498,
-.000729,.004946,
-.001015,.004895,
-.00129,.00483,
-.00044,.00398,
90.*
%
%ADD19MACRO19*%
%AMMACRO10*
4,1,15,.00398,.00044,
.003999,.000208,
.004004,-.000025,
.003996,-.000258,
.00398,-.00044,
.00483,-.00129,
.004897,-.001007,
.004947,-.000721,
.004981,-.000432,
.004997,-.000141,
.004997,.000149,
.00498,.00044,
.004946,.000729,
.004895,.001015,
.00483,.00129,
.00398,.00044,
0.0*
4,1,15,.00044,-.00398,
.000208,-.003999,
-.000025,-.004004,
-.000258,-.003996,
-.00044,-.00398,
-.00129,-.00483,
-.001007,-.004897,
-.000721,-.004947,
-.000432,-.004981,
-.000141,-.004997,
.000149,-.004997,
.00044,-.00498,
.000729,-.004946,
.001015,-.004895,
.00129,-.00483,
.00044,-.00398,
0.0*
4,1,15,-.00398,-.00044,
-.003999,-.000208,
-.004004,.000025,
-.003996,.000258,
-.00398,.00044,
-.00483,.00129,
-.004897,.001007,
-.004947,.000721,
-.004981,.000432,
-.004997,.000141,
-.004997,-.000149,
-.00498,-.00044,
-.004946,-.000729,
-.004895,-.001015,
-.00483,-.00129,
-.00398,-.00044,
0.0*
4,1,15,-.00044,.00398,
-.000208,.003999,
.000025,.004004,
.000258,.003996,
.00044,.00398,
.00129,.00483,
.001007,.004897,
.000721,.004947,
.000432,.004981,
.000141,.004997,
-.000149,.004997,
-.00044,.00498,
-.000729,.004946,
-.001015,.004895,
-.00129,.00483,
-.00044,.00398,
0.0*
%
%ADD10MACRO10*%
%ADD35C,.122*%
%ADD13C,.114*%
%ADD34C,.125*%
%ADD38C,.127*%
%ADD24C,.208*%
%ADD16O,.296X.162*%
%ADD40C,.147*%
%ADD27O,.072X.096*%
%ADD22C,.158*%
%ADD15C,.178*%
%ADD21C,.198*%
%AMMACRO42*
4,1,15,.00398,.00044,
.003999,.000208,
.004004,-.000025,
.003996,-.000258,
.00398,-.00044,
.00483,-.00129,
.004897,-.001007,
.004947,-.000721,
.004981,-.000432,
.004997,-.000141,
.004997,.000149,
.00498,.00044,
.004946,.000729,
.004895,.001015,
.00483,.00129,
.00398,.00044,
315.*
4,1,15,.00044,-.00398,
.000208,-.003999,
-.000025,-.004004,
-.000258,-.003996,
-.00044,-.00398,
-.00129,-.00483,
-.001007,-.004897,
-.000721,-.004947,
-.000432,-.004981,
-.000141,-.004997,
.000149,-.004997,
.00044,-.00498,
.000729,-.004946,
.001015,-.004895,
.00129,-.00483,
.00044,-.00398,
315.*
4,1,15,-.00398,-.00044,
-.003999,-.000208,
-.004004,.000025,
-.003996,.000258,
-.00398,.00044,
-.00483,.00129,
-.004897,.001007,
-.004947,.000721,
-.004981,.000432,
-.004997,.000141,
-.004997,-.000149,
-.00498,-.00044,
-.004946,-.000729,
-.004895,-.001015,
-.00483,-.00129,
-.00398,-.00044,
315.*
4,1,15,-.00044,.00398,
-.000208,.003999,
.000025,.004004,
.000258,.003996,
.00044,.00398,
.00129,.00483,
.001007,.004897,
.000721,.004947,
.000432,.004981,
.000141,.004997,
-.000149,.004997,
-.00044,.00498,
-.000729,.004946,
-.001015,.004895,
-.00129,.00483,
-.00044,.00398,
315.*
%
%ADD42MACRO42*%
%AMMACRO41*
4,1,15,.00398,.00044,
.003999,.000208,
.004004,-.000025,
.003996,-.000258,
.00398,-.00044,
.00483,-.00129,
.004897,-.001007,
.004947,-.000721,
.004981,-.000432,
.004997,-.000141,
.004997,.000149,
.00498,.00044,
.004946,.000729,
.004895,.001015,
.00483,.00129,
.00398,.00044,
135.*
4,1,15,.00044,-.00398,
.000208,-.003999,
-.000025,-.004004,
-.000258,-.003996,
-.00044,-.00398,
-.00129,-.00483,
-.001007,-.004897,
-.000721,-.004947,
-.000432,-.004981,
-.000141,-.004997,
.000149,-.004997,
.00044,-.00498,
.000729,-.004946,
.001015,-.004895,
.00129,-.00483,
.00044,-.00398,
135.*
4,1,15,-.00398,-.00044,
-.003999,-.000208,
-.004004,.000025,
-.003996,.000258,
-.00398,.00044,
-.00483,.00129,
-.004897,.001007,
-.004947,.000721,
-.004981,.000432,
-.004997,.000141,
-.004997,-.000149,
-.00498,-.00044,
-.004946,-.000729,
-.004895,-.001015,
-.00483,-.00129,
-.00398,-.00044,
135.*
4,1,15,-.00044,.00398,
-.000208,.003999,
.000025,.004004,
.000258,.003996,
.00044,.00398,
.00129,.00483,
.001007,.004897,
.000721,.004947,
.000432,.004981,
.000141,.004997,
-.000149,.004997,
-.00044,.00498,
-.000729,.004946,
-.001015,.004895,
-.00129,.00483,
-.00044,.00398,
135.*
%
%ADD41MACRO41*%
%AMMACRO18*
4,1,15,.00398,.00044,
.003999,.000208,
.004004,-.000025,
.003996,-.000258,
.00398,-.00044,
.00483,-.00129,
.004897,-.001007,
.004947,-.000721,
.004981,-.000432,
.004997,-.000141,
.004997,.000149,
.00498,.00044,
.004946,.000729,
.004895,.001015,
.00483,.00129,
.00398,.00044,
270.*
4,1,15,.00044,-.00398,
.000208,-.003999,
-.000025,-.004004,
-.000258,-.003996,
-.00044,-.00398,
-.00129,-.00483,
-.001007,-.004897,
-.000721,-.004947,
-.000432,-.004981,
-.000141,-.004997,
.000149,-.004997,
.00044,-.00498,
.000729,-.004946,
.001015,-.004895,
.00129,-.00483,
.00044,-.00398,
270.*
4,1,15,-.00398,-.00044,
-.003999,-.000208,
-.004004,.000025,
-.003996,.000258,
-.00398,.00044,
-.00483,.00129,
-.004897,.001007,
-.004947,.000721,
-.004981,.000432,
-.004997,.000141,
-.004997,-.000149,
-.00498,-.00044,
-.004946,-.000729,
-.004895,-.001015,
-.00483,-.00129,
-.00398,-.00044,
270.*
4,1,15,-.00044,.00398,
-.000208,.003999,
.000025,.004004,
.000258,.003996,
.00044,.00398,
.00129,.00483,
.001007,.004897,
.000721,.004947,
.000432,.004981,
.000141,.004997,
-.000149,.004997,
-.00044,.00498,
-.000729,.004946,
-.001015,.004895,
-.00129,.00483,
-.00044,.00398,
270.*
%
%ADD18MACRO18*%
%AMMACRO17*
4,1,15,.00398,.00044,
.003999,.000208,
.004004,-.000025,
.003996,-.000258,
.00398,-.00044,
.00483,-.00129,
.004897,-.001007,
.004947,-.000721,
.004981,-.000432,
.004997,-.000141,
.004997,.000149,
.00498,.00044,
.004946,.000729,
.004895,.001015,
.00483,.00129,
.00398,.00044,
180.*
4,1,15,.00044,-.00398,
.000208,-.003999,
-.000025,-.004004,
-.000258,-.003996,
-.00044,-.00398,
-.00129,-.00483,
-.001007,-.004897,
-.000721,-.004947,
-.000432,-.004981,
-.000141,-.004997,
.000149,-.004997,
.00044,-.00498,
.000729,-.004946,
.001015,-.004895,
.00129,-.00483,
.00044,-.00398,
180.*
4,1,15,-.00398,-.00044,
-.003999,-.000208,
-.004004,.000025,
-.003996,.000258,
-.00398,.00044,
-.00483,.00129,
-.004897,.001007,
-.004947,.000721,
-.004981,.000432,
-.004997,.000141,
-.004997,-.000149,
-.00498,-.00044,
-.004946,-.000729,
-.004895,-.001015,
-.00483,-.00129,
-.00398,-.00044,
180.*
4,1,15,-.00044,.00398,
-.000208,.003999,
.000025,.004004,
.000258,.003996,
.00044,.00398,
.00129,.00483,
.001007,.004897,
.000721,.004947,
.000432,.004981,
.000141,.004997,
-.000149,.004997,
-.00044,.00498,
-.000729,.004946,
-.001015,.004895,
-.00129,.00483,
-.00044,.00398,
180.*
%
%ADD17MACRO17*%
%AMMACRO37*
4,1,13,.02442,.01028,
.025834,.005883,
.026463,.001308,
.026288,-.003307,
.025315,-.007822,
.02442,-.01028,
.02819,-.01405,
.030201,-.008941,
.031295,-.003561,
.031438,.001927,
.030626,.007357,
.028883,.012564,
.02819,.01405,
.02442,.01028,
0.0*
4,1,13,.01028,-.02442,
.005883,-.025834,
.001308,-.026463,
-.003307,-.026288,
-.007822,-.025315,
-.01028,-.02442,
-.01405,-.02819,
-.008941,-.030201,
-.003561,-.031295,
.001927,-.031438,
.007357,-.030626,
.012564,-.028883,
.01405,-.02819,
.01028,-.02442,
0.0*
4,1,13,-.02442,-.01028,
-.025834,-.005883,
-.026463,-.001308,
-.026288,.003307,
-.025315,.007822,
-.02442,.01028,
-.02819,.01405,
-.030201,.008941,
-.031295,.003561,
-.031438,-.001927,
-.030626,-.007357,
-.028883,-.012564,
-.02819,-.01405,
-.02442,-.01028,
0.0*
4,1,13,-.01028,.02442,
-.005883,.025834,
-.001308,.026463,
.003307,.026288,
.007822,.025315,
.01028,.02442,
.01405,.02819,
.008941,.030201,
.003561,.031295,
-.001927,.031438,
-.007357,.030626,
-.012564,.028883,
-.01405,.02819,
-.01028,.02442,
0.0*
%
%ADD37MACRO37*%
%AMMACRO31*
4,1,19,.02172,.00757,
.022123,.006294,
.022452,.004997,
.022705,.003683,
.02288,.002357,
.022979,.001023,
.022999,-.000315,
.022942,-.001652,
.022807,-.002983,
.022595,-.004304,
.022307,-.005611,
.021943,-.006898,
.02172,-.00757,
.02556,-.01142,
.027155,-.006808,
.027924,-.001989,
.027846,.00289,
.026921,.007681,
.02556,.01142,
.02172,.00757,
0.0*
4,1,19,.00757,-.02172,
.006294,-.022123,
.004997,-.022452,
.003683,-.022705,
.002357,-.02288,
.001023,-.022979,
-.000315,-.022999,
-.001652,-.022942,
-.002983,-.022807,
-.004304,-.022595,
-.005611,-.022307,
-.006898,-.021943,
-.00757,-.02172,
-.01142,-.02556,
-.006808,-.027155,
-.001989,-.027924,
.00289,-.027846,
.007681,-.026921,
.01142,-.02556,
.00757,-.02172,
0.0*
4,1,19,-.02172,-.00757,
-.022123,-.006294,
-.022452,-.004997,
-.022705,-.003683,
-.02288,-.002357,
-.022979,-.001023,
-.022999,.000315,
-.022942,.001652,
-.022807,.002983,
-.022595,.004304,
-.022307,.005611,
-.021943,.006898,
-.02172,.00757,
-.02556,.01142,
-.027155,.006808,
-.027924,.001989,
-.027846,-.00289,
-.026921,-.007681,
-.02556,-.01142,
-.02172,-.00757,
0.0*
4,1,19,-.00757,.02172,
-.006294,.022123,
-.004997,.022452,
-.003683,.022705,
-.002357,.02288,
-.001023,.022979,
.000315,.022999,
.001652,.022942,
.002983,.022807,
.004304,.022595,
.005611,.022307,
.006898,.021943,
.00757,.02172,
.01142,.02556,
.006808,.027155,
.001989,.027924,
-.00289,.027846,
-.007681,.026921,
-.01142,.02556,
-.00757,.02172,
0.0*
%
%ADD31MACRO31*%
%ADD43C,.02*%
%ADD44C,.006*%
%ADD53C,.07204*%
%ADD52C,.05604*%
%ADD54C,.05804*%
%ADD47C,.11004*%
%ADD55C,.12104*%
%ADD56C,.11804*%
%ADD50C,.15404*%
%ADD45O,.29202X.15802*%
%ADD57C,.23626*%
%ADD46O,.29204X.15804*%
%ADD58C,.2369*%
%ADD51C,.2964*%
%ADD48C,.37554*%
%ADD49C,.37566*%
G75*
%LPD*%
G75*
G36*
G01X-6000Y-6000D02*
X931197D01*
Y769780D01*
X-6000D01*
Y-6000D01*
G37*
%LPC*%
G75*
G36*
G01X903913Y760260D02*
X922094Y723897D01*
G02X922193Y723480I-834J-418D01*
G01Y3937D01*
G02X921260Y3004I-933J0D01*
G01X291457D01*
G02X290524Y3937I0J933D01*
G01Y429331D01*
G03X283583Y436272I-6941J0D01*
G01X124134D01*
G03X117193Y429331I0J-6941D01*
G01Y3937D01*
G02X116260Y3004I-933J0D01*
G01X3937D01*
G02X3004Y3937I0J933D01*
G01Y723480D01*
G02X3103Y723897I933J-1D01*
G01X21284Y760260D01*
G02X22118Y760776I835J-417D01*
G01X386150D01*
G02X386984Y760260I-1J-933D01*
G01X405165Y723897D01*
G02X405264Y723480I-834J-418D01*
G01Y188976D01*
G03X414199Y185972I4973J0D01*
G01X562179D01*
G03X571114Y188976I3962J3004D01*
G01Y723480D01*
G02X571213Y723897I933J-1D01*
G01X589394Y760260D01*
G02X590228Y760776I835J-417D01*
G01X903079D01*
G02X903913Y760260I-1J-933D01*
G37*
%LPD*%
G75*
G36*
G01X796849Y298753D02*
G02Y295733I0J-1510D01*
G01X793699D01*
G02X793700Y298753I1J1510D01*
G01X796849D01*
G37*
G36*
G01X793417Y317698D02*
G02X793216Y317900I1J202D01*
G01Y321100D01*
G02X793417Y321302I201J1D01*
G01X794217D01*
G02X794418Y321100I-1J-202D01*
G01Y317900D01*
G02X794217Y317698I-201J-1D01*
G01X793417D01*
G37*
G36*
G01X791217D02*
G02X791016Y317900I1J202D01*
G01Y321100D01*
G02X791217Y321302I201J1D01*
G01X792017D01*
G02X792218Y321100I-1J-202D01*
G01Y317900D01*
G02X792017Y317698I-201J-1D01*
G01X791217D01*
G37*
G36*
G01X788417D02*
G02X788216Y317900I1J202D01*
G01Y321100D01*
G02X788417Y321302I201J1D01*
G01X789217D01*
G02X789418Y321100I-1J-202D01*
G01Y317900D01*
G02X789217Y317698I-201J-1D01*
G01X788417D01*
G37*
G36*
G01X786217D02*
G02X786016Y317900I1J202D01*
G01Y321100D01*
G02X786217Y321302I201J1D01*
G01X787017D01*
G02X787218Y321100I-1J-202D01*
G01Y317900D01*
G02X787017Y317698I-201J-1D01*
G01X786217D01*
G37*
G36*
G01X783417D02*
G02X783216Y317900I1J202D01*
G01Y321100D01*
G02X783417Y321302I201J1D01*
G01X784217D01*
G02X784418Y321100I-1J-202D01*
G01Y317900D01*
G02X784217Y317698I-201J-1D01*
G01X783417D01*
G37*
G36*
G01X781217D02*
G02X781016Y317900I1J202D01*
G01Y321100D01*
G02X781217Y321302I201J1D01*
G01X782017D01*
G02X782218Y321100I-1J-202D01*
G01Y317900D01*
G02X782017Y317698I-201J-1D01*
G01X781217D01*
G37*
G36*
G01X778417D02*
G02X778216Y317900I1J202D01*
G01Y321100D01*
G02X778417Y321302I201J1D01*
G01X779217D01*
G02X779418Y321100I-1J-202D01*
G01Y317900D01*
G02X779217Y317698I-201J-1D01*
G01X778417D01*
G37*
G36*
G01X776217D02*
G02X776016Y317900I1J202D01*
G01Y321100D01*
G02X776217Y321302I201J1D01*
G01X777017D01*
G02X777218Y321100I-1J-202D01*
G01Y317900D01*
G02X777017Y317698I-201J-1D01*
G01X776217D01*
G37*
G36*
G01X761417D02*
G02X761216Y317900I1J202D01*
G01Y321100D01*
G02X761417Y321302I201J1D01*
G01X762217D01*
G02X762418Y321100I-1J-202D01*
G01Y317900D01*
G02X762217Y317698I-201J-1D01*
G01X761417D01*
G37*
G36*
G01X759217D02*
G02X759016Y317900I1J202D01*
G01Y321100D01*
G02X759217Y321302I201J1D01*
G01X760017D01*
G02X760218Y321100I-1J-202D01*
G01Y317900D01*
G02X760017Y317698I-201J-1D01*
G01X759217D01*
G37*
G36*
G01X756417D02*
G02X756216Y317900I1J202D01*
G01Y321100D01*
G02X756417Y321302I201J1D01*
G01X757217D01*
G02X757418Y321100I-1J-202D01*
G01Y317900D01*
G02X757217Y317698I-201J-1D01*
G01X756417D01*
G37*
G36*
G01X754217D02*
G02X754016Y317900I1J202D01*
G01Y321100D01*
G02X754217Y321302I201J1D01*
G01X755017D01*
G02X755218Y321100I-1J-202D01*
G01Y317900D01*
G02X755017Y317698I-201J-1D01*
G01X754217D01*
G37*
G36*
G01X748417D02*
G02X748216Y317900I1J202D01*
G01Y321100D01*
G02X748417Y321302I201J1D01*
G01X749217D01*
G02X749418Y321100I-1J-202D01*
G01Y317900D01*
G02X749217Y317698I-201J-1D01*
G01X748417D01*
G37*
G36*
G01X746217D02*
G02X746016Y317900I1J202D01*
G01Y321100D01*
G02X746217Y321302I201J1D01*
G01X747017D01*
G02X747218Y321100I-1J-202D01*
G01Y317900D01*
G02X747017Y317698I-201J-1D01*
G01X746217D01*
G37*
G36*
G01X741917D02*
G02X741716Y317900I1J202D01*
G01Y321100D01*
G02X741917Y321302I201J1D01*
G01X742717D01*
G02X742918Y321100I-1J-202D01*
G01Y317900D01*
G02X742717Y317698I-201J-1D01*
G01X741917D01*
G37*
G36*
G01X739717D02*
G02X739516Y317900I1J202D01*
G01Y321100D01*
G02X739717Y321302I201J1D01*
G01X740517D01*
G02X740718Y321100I-1J-202D01*
G01Y317900D01*
G02X740517Y317698I-201J-1D01*
G01X739717D01*
G37*
G36*
G01X753085Y74898D02*
G02X752884Y75100I1J202D01*
G01Y75900D01*
G02X753085Y76102I201J1D01*
G01X756285D01*
G02X756486Y75900I-1J-202D01*
G01Y75100D01*
G02X756285Y74898I-201J-1D01*
G01X753085D01*
G37*
G36*
G01Y77398D02*
G02X752884Y77600I1J202D01*
G01Y78400D01*
G02X753085Y78602I201J1D01*
G01X756285D01*
G02X756486Y78400I-1J-202D01*
G01Y77600D01*
G02X756285Y77398I-201J-1D01*
G01X753085D01*
G37*
G36*
G01Y82898D02*
G02X752884Y83100I1J202D01*
G01Y83900D01*
G02X753085Y84102I201J1D01*
G01X756285D01*
G02X756486Y83900I-1J-202D01*
G01Y83100D01*
G02X756285Y82898I-201J-1D01*
G01X753085D01*
G37*
G36*
G01Y85398D02*
G02X752884Y85600I1J202D01*
G01Y86400D01*
G02X753085Y86602I201J1D01*
G01X756285D01*
G02X756486Y86400I-1J-202D01*
G01Y85600D01*
G02X756285Y85398I-201J-1D01*
G01X753085D01*
G37*
G36*
G01Y90898D02*
G02X752884Y91100I1J202D01*
G01Y91900D01*
G02X753085Y92102I201J1D01*
G01X756285D01*
G02X756486Y91900I-1J-202D01*
G01Y91100D01*
G02X756285Y90898I-201J-1D01*
G01X753085D01*
G37*
G36*
G01Y93398D02*
G02X752884Y93600I1J202D01*
G01Y94400D01*
G02X753085Y94602I201J1D01*
G01X756285D01*
G02X756486Y94400I-1J-202D01*
G01Y93600D01*
G02X756285Y93398I-201J-1D01*
G01X753085D01*
G37*
G36*
G01X753084Y98898D02*
G02X752882Y99100I0J202D01*
G01Y99900D01*
G02X753084Y100102I202J0D01*
G01X756284D01*
G02X756486Y99900I0J-202D01*
G01Y99100D01*
G02X756284Y98898I-202J0D01*
G01X753084D01*
G37*
G36*
G01Y101398D02*
G02X752882Y101600I0J202D01*
G01Y102400D01*
G02X753084Y102602I202J0D01*
G01X756284D01*
G02X756486Y102400I0J-202D01*
G01Y101600D01*
G02X756284Y101398I-202J0D01*
G01X753084D01*
G37*
G36*
G01X668785Y149546D02*
G02X668584Y149747I0J201D01*
G01Y152947D01*
G02X668785Y153148I201J0D01*
G01X669585D01*
G02X669786Y152947I0J-201D01*
G01Y149747D01*
G02X669585Y149546I-201J0D01*
G01X668785D01*
G37*
G36*
G01X703980Y104192D02*
G02X707438Y106044I1729J926D01*
G01X710371Y100567D01*
X710372Y100565D01*
G02X706932Y98680I-1711J-959D01*
G01X703980Y104192D01*
G37*
G36*
G01X712838Y104191D02*
G02X716296Y106045I1729J927D01*
G01X719230Y100567D01*
X719231Y100565D01*
G02X715791Y98679I-1711J-959D01*
G01X712838Y104191D01*
G37*
G36*
G01X666285Y149546D02*
G02X666084Y149747I0J201D01*
G01Y152947D01*
G02X666285Y153148I201J0D01*
G01X667085D01*
G02X667286Y152947I0J-201D01*
G01Y149747D01*
G02X667085Y149546I-201J0D01*
G01X666285D01*
G37*
G36*
G01X663384D02*
G02X663182Y149747I-1J201D01*
G01Y152947D01*
G02X663384Y153148I202J-1D01*
G01X664184D01*
G02X664386Y152947I1J-201D01*
G01Y149747D01*
G02X664184Y149546I-202J1D01*
G01X663384D01*
G37*
G36*
G01X660884D02*
G02X660682Y149747I-1J201D01*
G01Y152947D01*
G02X660884Y153148I202J-1D01*
G01X661684D01*
G02X661886Y152947I1J-201D01*
G01Y149747D01*
G02X661684Y149546I-202J1D01*
G01X660884D01*
G37*
G36*
G01X658185Y149446D02*
G02X657984Y149647I0J201D01*
G01Y152847D01*
G02X658185Y153048I201J0D01*
G01X658985D01*
G02X659186Y152847I0J-201D01*
G01Y149647D01*
G02X658985Y149446I-201J0D01*
G01X658185D01*
G37*
G36*
G01X655685D02*
G02X655484Y149647I0J201D01*
G01Y152847D01*
G02X655685Y153048I201J0D01*
G01X656485D01*
G02X656686Y152847I0J-201D01*
G01Y149647D01*
G02X656485Y149446I-201J0D01*
G01X655685D01*
G37*
G36*
G01X652984D02*
G02X652782Y149647I-1J201D01*
G01Y152847D01*
G02X652984Y153048I202J-1D01*
G01X653784D01*
G02X653986Y152847I1J-201D01*
G01Y149647D01*
G02X653784Y149446I-202J1D01*
G01X652984D01*
G37*
G36*
G01X650484D02*
G02X650282Y149647I-1J201D01*
G01Y152847D01*
G02X650484Y153048I202J-1D01*
G01X651284D01*
G02X651486Y152847I1J-201D01*
G01Y149647D01*
G02X651284Y149446I-202J1D01*
G01X650484D01*
G37*
G36*
G01X336094Y334271D02*
G02X333070I-1512J0D01*
G01Y337772D01*
G02X336094Y337771I1512J-1D01*
G01Y334271D01*
G37*
G36*
G01X305778Y340592D02*
G02X302756I-1511J0D01*
G01Y344093D01*
G02X305778Y344092I1511J-1D01*
G01Y340592D01*
G37*
G36*
G01X309078Y353192D02*
G02X306056I-1511J0D01*
G01Y356693D01*
G02X309078Y356692I1511J-1D01*
G01Y353192D01*
G37*
G36*
G01X305778Y365792D02*
G02X302756I-1511J0D01*
G01Y369293D01*
G02X305778Y369292I1511J-1D01*
G01Y365792D01*
G37*
G36*
G01X326670Y350371D02*
G02X329694I1512J0D01*
G01Y346870D01*
G02X326670Y346871I-1512J1D01*
G01Y350371D01*
G37*
G36*
G01X336094Y359474D02*
G02X333070I-1512J0D01*
G01Y362975D01*
G02X336094Y362974I1512J-1D01*
G01Y359474D01*
G37*
G36*
G01X329694Y372018D02*
G02X326670I-1512J0D01*
G01Y375519D01*
G02X329694Y375518I1512J-1D01*
G01Y372018D01*
G37*
G36*
G01X305778Y315392D02*
G02X302756I-1511J0D01*
G01Y318893D01*
G02X305778Y318892I1511J-1D01*
G01Y315392D01*
G37*
G36*
G01X309078Y277592D02*
G02X306056I-1511J0D01*
G01Y281093D01*
G02X309078Y281092I1511J-1D01*
G01Y277592D01*
G37*
G36*
G01X305778Y290192D02*
G02X302756I-1511J0D01*
G01Y293693D01*
G02X305778Y293692I1511J-1D01*
G01Y290192D01*
G37*
G36*
G01X333070Y287284D02*
G02X336094I1512J0D01*
G01Y283783D01*
G02X333070Y283784I-1512J1D01*
G01Y287284D01*
G37*
G36*
G01X309078Y302792D02*
G02X306056I-1511J0D01*
G01Y306293D01*
G02X309078Y306292I1511J-1D01*
G01Y302792D01*
G37*
G36*
G01X329694Y296477D02*
G02X326670I-1512J0D01*
G01Y299978D01*
G02X329694Y299977I1512J-1D01*
G01Y296477D01*
G37*
G36*
G01X336094Y309074D02*
G02X333070I-1512J0D01*
G01Y312575D01*
G02X336094Y312574I1512J-1D01*
G01Y309074D01*
G37*
G36*
G01X329694Y321674D02*
G02X326670I-1512J0D01*
G01Y325175D01*
G02X329694Y325174I1512J-1D01*
G01Y321674D01*
G37*
G36*
G01X309078Y328092D02*
G02X306056I-1511J0D01*
G01Y331593D01*
G02X309078Y331592I1511J-1D01*
G01Y328092D01*
G37*
G36*
G01X302720Y268548D02*
G02X305742I1511J0D01*
G01Y265047D01*
G02X302720Y265048I-1511J1D01*
G01Y268548D01*
G37*
G36*
G01X781670Y347206D02*
X781669Y347207D01*
X779234Y349642D01*
X779232Y349644D01*
G02X781330Y351794I1031J1093D01*
G01X783794Y349330D01*
G02X781670Y347206I-1057J-1067D01*
G37*
G36*
G01X764148Y351494D02*
X766612Y349030D01*
G02X764488Y346906I-1057J-1067D01*
G01X764487Y346907D01*
X762052Y349342D01*
X762050Y349344D01*
G02X764148Y351494I1031J1093D01*
G37*
G36*
G01X753430Y344794D02*
X755894Y342330D01*
G02X753770Y340206I-1057J-1067D01*
G01X753769Y340207D01*
X751334Y342642D01*
X751332Y342644D01*
G02X753430Y344794I1031J1093D01*
G37*
G36*
G01X793570Y335406D02*
X793569Y335407D01*
X791134Y337842D01*
X791132Y337844D01*
G02X793230Y339994I1031J1093D01*
G01X795694Y337530D01*
G02X793570Y335406I-1057J-1067D01*
G37*
G36*
G01X776248Y339494D02*
X778712Y337030D01*
G02X776588Y334906I-1057J-1067D01*
G01X776587Y334907D01*
X774152Y337342D01*
X774150Y337344D01*
G02X776248Y339494I1031J1093D01*
G37*
G36*
G01X803770Y333106D02*
X803769Y333107D01*
X801334Y335542D01*
X801332Y335544D01*
G02X803430Y337694I1031J1093D01*
G01X805894Y335230D01*
G02X803770Y333106I-1057J-1067D01*
G37*
G36*
G01X747330Y333794D02*
X749794Y331330D01*
G02X747670Y329206I-1057J-1067D01*
G01X747669Y329207D01*
X745234Y331642D01*
X745232Y331644D01*
G02X747330Y333794I1031J1093D01*
G37*
G36*
G01X765370Y328306D02*
X765369Y328307D01*
X762934Y330742D01*
X762932Y330744D01*
G02X765030Y332894I1031J1093D01*
G01X767494Y330430D01*
G02X765370Y328306I-1057J-1067D01*
G37*
G36*
G01X849476Y314648D02*
X849477Y314647D01*
X852620Y311503D01*
X852622Y311501D01*
G02X850524Y309352I-1031J-1092D01*
G01X847352Y312524D01*
G02X849476Y314648I1057J1067D01*
G37*
G36*
G01X853976Y299148D02*
X853977Y299147D01*
X857120Y296003D01*
X857122Y296001D01*
G02X855024Y293852I-1031J-1092D01*
G01X851852Y297024D01*
G02X853976Y299148I1057J1067D01*
G37*
G36*
G01X847976Y293148D02*
X847977Y293147D01*
X851120Y290003D01*
X851122Y290001D01*
G02X849024Y287852I-1031J-1092D01*
G01X845852Y291024D01*
G02X847976Y293148I1057J1067D01*
G37*
G36*
G01X842476Y287648D02*
X842477Y287647D01*
X845620Y284503D01*
X845622Y284501D01*
G02X843524Y282352I-1031J-1092D01*
G01X840352Y285524D01*
G02X842476Y287648I1057J1067D01*
G37*
G36*
G01X844476Y274648D02*
X844477Y274647D01*
X847620Y271503D01*
X847622Y271501D01*
G02X845524Y269352I-1031J-1092D01*
G01X842352Y272524D01*
G02X844476Y274648I1057J1067D01*
G37*
G36*
G01X838476Y268848D02*
X838477Y268847D01*
X841620Y265703D01*
X841622Y265701D01*
G02X839524Y263552I-1031J-1092D01*
G01X836352Y266724D01*
G02X838476Y268848I1057J1067D01*
G37*
G36*
G01X832676Y262348D02*
X832677Y262347D01*
X835820Y259203D01*
X835822Y259201D01*
G02X833724Y257052I-1031J-1092D01*
G01X830552Y260224D01*
G02X832676Y262348I1057J1067D01*
G37*
G36*
G01X832012Y252729D02*
X832013Y252728D01*
X835156Y249584D01*
X835158Y249582D01*
G02X833060Y247433I-1031J-1092D01*
G01X829888Y250605D01*
G02X832012Y252729I1057J1067D01*
G37*
G36*
G01X551124Y149798D02*
Y145478D01*
X551132Y145450D01*
G02X547292I-1920J-568D01*
G01X547300Y145478D01*
Y149798D01*
X547292Y149826D01*
G02X551132I1920J568D01*
G01X551124Y149798D01*
G37*
G36*
G01X536950D02*
Y145478D01*
X536959Y145450D01*
G02X533119I-1920J-568D01*
G01X533128Y145478D01*
Y149798D01*
X533119Y149826D01*
G02X536959I1920J568D01*
G01X536950Y149798D01*
G37*
G36*
G01X522778D02*
Y145478D01*
X522786Y145450D01*
G02X518946I-1920J-568D01*
G01X518954Y145478D01*
Y149798D01*
X518946Y149826D01*
G02X522786I1920J568D01*
G01X522778Y149798D01*
G37*
G36*
G01X508604D02*
Y145478D01*
X508613Y145450D01*
G02X504773I-1920J-568D01*
G01X504782Y145478D01*
Y149798D01*
X504773Y149826D01*
G02X508613I1920J568D01*
G01X508604Y149798D01*
G37*
G36*
G01X466084D02*
Y145478D01*
X466093Y145450D01*
G02X462253I-1920J-568D01*
G01X462262Y145478D01*
Y149798D01*
X462253Y149826D01*
G02X466093I1920J568D01*
G01X466084Y149798D01*
G37*
G36*
G01X451912D02*
Y145478D01*
X451920Y145450D01*
G02X448080I-1920J-568D01*
G01X448088Y145478D01*
Y149798D01*
X448080Y149826D01*
G02X451920I1920J568D01*
G01X451912Y149798D01*
G37*
G36*
G01X437738D02*
Y145478D01*
X437747Y145450D01*
G02X433907I-1920J-568D01*
G01X433916Y145478D01*
Y149798D01*
X433907Y149826D01*
G02X437747I1920J568D01*
G01X437738Y149798D01*
G37*
G36*
G01X423564D02*
Y145478D01*
X423573Y145450D01*
G02X419733I-1920J-568D01*
G01X419742Y145478D01*
Y149798D01*
X419733Y149826D01*
G02X423573I1920J568D01*
G01X423564Y149798D01*
G37*
G36*
G01X558210Y145074D02*
Y140754D01*
X558219Y140726D01*
G02X554379I-1920J-568D01*
G01X554388Y140754D01*
Y145074D01*
X554379Y145102D01*
G02X558219I1920J568D01*
G01X558210Y145074D01*
G37*
G36*
G01X544038D02*
Y140754D01*
X544046Y140726D01*
G02X540206I-1920J-568D01*
G01X540214Y140754D01*
Y145074D01*
X540206Y145102D01*
G02X544046I1920J568D01*
G01X544038Y145074D01*
G37*
G36*
G01X529864D02*
Y140754D01*
X529873Y140726D01*
G02X526033I-1920J-568D01*
G01X526042Y140754D01*
Y145074D01*
X526033Y145102D01*
G02X529873I1920J568D01*
G01X529864Y145074D01*
G37*
G36*
G01X515690D02*
Y140754D01*
X515699Y140726D01*
G02X511859I-1920J-568D01*
G01X511868Y140754D01*
Y145074D01*
X511859Y145102D01*
G02X515699I1920J568D01*
G01X515690Y145074D01*
G37*
G36*
G01X473172D02*
Y140754D01*
X473180Y140726D01*
G02X469340I-1920J-568D01*
G01X469348Y140754D01*
Y145074D01*
X469340Y145102D01*
G02X473180I1920J568D01*
G01X473172Y145074D01*
G37*
G36*
G01X458998D02*
Y140754D01*
X459006Y140726D01*
G02X455166I-1920J-568D01*
G01X455174Y140754D01*
Y145074D01*
X455166Y145102D01*
G02X459006I1920J568D01*
G01X458998Y145074D01*
G37*
G36*
G01X444824D02*
Y140754D01*
X444833Y140726D01*
G02X440993I-1920J-568D01*
G01X441002Y140754D01*
Y145074D01*
X440993Y145102D01*
G02X444833I1920J568D01*
G01X444824Y145074D01*
G37*
G36*
G01X430652D02*
Y140754D01*
X430660Y140726D01*
G02X426820I-1920J-568D01*
G01X426828Y140754D01*
Y145074D01*
X426820Y145102D01*
G02X430660I1920J568D01*
G01X430652Y145074D01*
G37*
G36*
G01X551124Y135625D02*
Y131305D01*
X551132Y131277D01*
G02X547292I-1920J-568D01*
G01X547300Y131305D01*
Y135625D01*
X547292Y135653D01*
G02X551132I1920J568D01*
G01X551124Y135625D01*
G37*
G36*
G01X536950D02*
Y131305D01*
X536959Y131277D01*
G02X533119I-1920J-568D01*
G01X533128Y131305D01*
Y135625D01*
X533119Y135653D01*
G02X536959I1920J568D01*
G01X536950Y135625D01*
G37*
G36*
G01X522778D02*
Y131305D01*
X522786Y131277D01*
G02X518946I-1920J-568D01*
G01X518954Y131305D01*
Y135625D01*
X518946Y135653D01*
G02X522786I1920J568D01*
G01X522778Y135625D01*
G37*
G36*
G01X508604D02*
Y131305D01*
X508613Y131277D01*
G02X504773I-1920J-568D01*
G01X504782Y131305D01*
Y135625D01*
X504773Y135653D01*
G02X508613I1920J568D01*
G01X508604Y135625D01*
G37*
G36*
G01X466084D02*
Y131305D01*
X466093Y131277D01*
G02X462253I-1920J-568D01*
G01X462262Y131305D01*
Y135625D01*
X462253Y135653D01*
G02X466093I1920J568D01*
G01X466084Y135625D01*
G37*
G36*
G01X451912D02*
Y131305D01*
X451920Y131277D01*
G02X448080I-1920J-568D01*
G01X448088Y131305D01*
Y135625D01*
X448080Y135653D01*
G02X451920I1920J568D01*
G01X451912Y135625D01*
G37*
G36*
G01X437738D02*
Y131305D01*
X437747Y131277D01*
G02X433907I-1920J-568D01*
G01X433916Y131305D01*
Y135625D01*
X433907Y135653D01*
G02X437747I1920J568D01*
G01X437738Y135625D01*
G37*
G36*
G01X423564D02*
Y131305D01*
X423573Y131277D01*
G02X419733I-1920J-568D01*
G01X419742Y131305D01*
Y135625D01*
X419733Y135653D01*
G02X423573I1920J568D01*
G01X423564Y135625D01*
G37*
G36*
G01X558210Y130900D02*
Y126581D01*
X558219Y126553D01*
G02X554379I-1920J-568D01*
G01X554388Y126581D01*
Y130900D01*
X554379Y130928D01*
G02X558219I1920J568D01*
G01X558210Y130900D01*
G37*
G36*
G01X544038D02*
Y126581D01*
X544046Y126553D01*
G02X540206I-1920J-568D01*
G01X540214Y126581D01*
Y130900D01*
X540206Y130928D01*
G02X544046I1920J568D01*
G01X544038Y130900D01*
G37*
G36*
G01X529864D02*
Y126581D01*
X529873Y126553D01*
G02X526033I-1920J-568D01*
G01X526042Y126581D01*
Y130900D01*
X526033Y130928D01*
G02X529873I1920J568D01*
G01X529864Y130900D01*
G37*
G36*
G01X515690D02*
Y126581D01*
X515699Y126553D01*
G02X511859I-1920J-568D01*
G01X511868Y126581D01*
Y130900D01*
X511859Y130928D01*
G02X515699I1920J568D01*
G01X515690Y130900D01*
G37*
G36*
G01X473172D02*
Y126581D01*
X473180Y126553D01*
G02X469340I-1920J-568D01*
G01X469348Y126581D01*
Y130900D01*
X469340Y130928D01*
G02X473180I1920J568D01*
G01X473172Y130900D01*
G37*
G36*
G01X458998D02*
Y126581D01*
X459006Y126553D01*
G02X455166I-1920J-568D01*
G01X455174Y126581D01*
Y130900D01*
X455166Y130928D01*
G02X459006I1920J568D01*
G01X458998Y130900D01*
G37*
G36*
G01X444824D02*
Y126581D01*
X444833Y126553D01*
G02X440993I-1920J-568D01*
G01X441002Y126581D01*
Y130900D01*
X440993Y130928D01*
G02X444833I1920J568D01*
G01X444824Y130900D01*
G37*
G36*
G01X430652D02*
Y126581D01*
X430660Y126553D01*
G02X426820I-1920J-568D01*
G01X426828Y126581D01*
Y130900D01*
X426820Y130928D01*
G02X430660I1920J568D01*
G01X430652Y130900D01*
G37*
G36*
G01X715607Y114177D02*
X715602Y114206D01*
X713203Y118682D01*
X713183Y118703D01*
G02X716480Y120469I1384J1376D01*
G01X716485Y120440D01*
X718883Y115964D01*
X718904Y115944D01*
G02X715607Y114177I-1384J-1377D01*
G37*
G36*
G01X706748D02*
X706742Y114206D01*
X704345Y118682D01*
X704325Y118703D01*
G02X707622Y120469I1384J1376D01*
G01X707628Y120440D01*
X710024Y115964D01*
X710045Y115943D01*
G02X706748Y114177I-1384J-1376D01*
G37*
G36*
G01X636867D02*
X636862Y114206D01*
X634463Y118682D01*
X634443Y118703D01*
G02X637740Y120469I1384J1376D01*
G01X637745Y120440D01*
X640143Y115964D01*
X640164Y115944D01*
G02X636867Y114177I-1384J-1377D01*
G37*
G36*
G01X628882Y120469D02*
X628888Y120440D01*
X631284Y115964D01*
X631305Y115943D01*
G02X628008Y114177I-1384J-1376D01*
G01X628002Y114206D01*
X625605Y118682D01*
X625585Y118703D01*
G02X628882Y120469I1384J1376D01*
G37*
G36*
G01X636867Y99216D02*
X636862Y99245D01*
X634463Y103721D01*
X634443Y103742D01*
G02X637740Y105508I1384J1376D01*
G01X637745Y105479D01*
X640143Y101003D01*
X640164Y100983D01*
G02X636867Y99216I-1384J-1377D01*
G37*
G36*
G01X628882Y105508D02*
X628888Y105479D01*
X631284Y101003D01*
X631305Y100982D01*
G02X628008Y99216I-1384J-1376D01*
G01X628002Y99245D01*
X625605Y103721D01*
X625585Y103742D01*
G02X628882Y105508I1384J1376D01*
G37*
G36*
G01X715614Y84226D02*
X715608Y84253D01*
X713181Y88783D01*
X713161Y88803D01*
G02X716473Y90577I1406J1354D01*
G01X716479Y90550D01*
X718907Y86019D01*
X718927Y85999D01*
G02X715614Y84226I-1407J-1353D01*
G37*
G36*
G01X706748Y84256D02*
X706742Y84285D01*
X704346Y88760D01*
X704325Y88780D01*
G02X707622Y90547I1384J1377D01*
G01X707628Y90518D01*
X710025Y86043D01*
X710045Y86022D01*
G02X706748Y84256I-1384J-1376D01*
G37*
G36*
G01X636874Y84226D02*
X636868Y84253D01*
X634441Y88783D01*
X634421Y88803D01*
G02X637733Y90577I1406J1354D01*
G01X637739Y90550D01*
X640167Y86019D01*
X640187Y85999D01*
G02X636874Y84226I-1407J-1353D01*
G37*
G36*
G01X628882Y90547D02*
X628888Y90518D01*
X631285Y86043D01*
X631305Y86022D01*
G02X628008Y84256I-1384J-1376D01*
G01X628002Y84285D01*
X625606Y88760D01*
X625585Y88780D01*
G02X628882Y90547I1384J1377D01*
G37*
G36*
G01X715607Y69295D02*
X715602Y69324D01*
X713203Y73800D01*
X713183Y73821D01*
G02X716480Y75587I1384J1376D01*
G01X716485Y75558D01*
X718883Y71082D01*
X718904Y71062D01*
G02X715607Y69295I-1384J-1377D01*
G37*
G36*
G01X706748D02*
X706742Y69324D01*
X704345Y73800D01*
X704325Y73821D01*
G02X707622Y75587I1384J1376D01*
G01X707628Y75558D01*
X710024Y71082D01*
X710045Y71061D01*
G02X706748Y69295I-1384J-1376D01*
G37*
G36*
G01X636867D02*
X636862Y69324D01*
X634463Y73800D01*
X634443Y73821D01*
G02X637740Y75587I1384J1376D01*
G01X637745Y75558D01*
X640143Y71082D01*
X640164Y71062D01*
G02X636867Y69295I-1384J-1377D01*
G37*
G36*
G01X628882Y75587D02*
X628888Y75558D01*
X631284Y71082D01*
X631305Y71061D01*
G02X628008Y69295I-1384J-1376D01*
G01X628002Y69324D01*
X625605Y73800D01*
X625585Y73821D01*
G02X628882Y75587I1384J1376D01*
G37*
G36*
G01X769908Y294122D02*
X769913Y290947D01*
G02X767276Y290250I-1410J-2D01*
G03X766580I-348J-197D01*
G02X763943Y290931I-1227J695D01*
G01X763915Y294089D01*
G02X766556Y294789I1410J13D01*
G03X767257Y294794I349J195D01*
G02X769908Y294126I1241J-670D01*
G01Y294122D01*
G37*
G36*
G01X779362Y290928D02*
G02X776725Y290250I-1410J17D01*
G03X776029I-348J-197D01*
G02X773392Y290959I-1227J695D01*
G01X773425Y294103D01*
G02X776062Y294782I1410J-15D01*
G03X776759Y294783I348J197D01*
G02X779399Y294076I1230J-690D01*
G01X779362Y290928D01*
G37*
G36*
G01X760464Y290945D02*
G02X757827Y290249I-1410J-1D01*
G03X757132I-348J-198D01*
G02X754495Y290944I-1227J695D01*
G01Y294093D01*
G02X757132Y294788I1410J0D01*
G03X757828I348J197D01*
G02X760465Y294093I1227J-694D01*
G01X760464Y290945D01*
G37*
G36*
G01X788818Y294071D02*
X788814Y292330D01*
G03X789493Y292042I400J-1D01*
G02X790545Y292469I1052J-1082D01*
G01X793694D01*
G02X794830Y289964I0J-1510D01*
G03X795130Y289301I301J-263D01*
G01X796845Y289294D01*
G02X796833Y286274I-6J-1510D01*
G01X795125Y286281D01*
G03X794820Y285620I-2J-400D01*
G02X795185Y284639I-1145J-984D01*
G01Y284634D01*
X795189Y281510D01*
G02X794829Y280529I-1510J-2D01*
G03X795134Y279870I305J-259D01*
G01X796865Y279874D01*
G02X796871Y276854I3J-1510D01*
G01X795176Y276850D01*
G03X794876Y276188I2J-400D01*
G02X795247Y275169I-1139J-992D01*
G01X795192Y272037D01*
G02X794817Y271067I-1510J26D01*
G03X795121Y270403I300J-264D01*
G01X796835Y270420D01*
G02X796865Y267400I15J-1510D01*
G01X795135Y267383D01*
G03X794832Y266726I4J-400D01*
G02X795184Y265770I-1158J-969D01*
G01X795209Y262646D01*
G02X792189Y262622I-1510J-12D01*
G01X792164Y265745D01*
G02X792807Y266994I1510J13D01*
G03X792809Y267648I-229J328D01*
G02X792849Y270138I874J1231D01*
G03Y270804I-221J333D01*
G02X792172Y272091I833J1260D01*
G01X792227Y275222D01*
G02X792865Y276429I1510J-26D01*
G03X792853Y277091I-230J327D01*
G02X792823Y279604I822J1266D01*
G03X792824Y280263I-226J330D01*
G02X792169Y281506I855J1245D01*
G01X792165Y284634D01*
G02X792838Y285893I1510J2D01*
G03X792844Y286555I-221J333D01*
G02X792563Y288787I859J1242D01*
G03X792261Y289449I-302J262D01*
G01X790544D01*
G02X789259Y290168I1J1510D01*
G03X788583Y290176I-341J-210D01*
G02X786174Y290250I-1182J769D01*
G03X785478I-348J-197D01*
G02X782841Y290947I-1227J695D01*
G01X782848Y294067D01*
G02X785483Y294763I1410J-3D01*
G03X786179Y294765I347J198D01*
G02X788818Y294071I1229J-691D01*
G37*
G54D53*
X305906Y182874D03*
G54D52*
X201801Y684252D03*
X225601D03*
G54D54*
X305906Y388386D03*
G54D47*
X18700Y54650D03*
X901000Y21400D03*
X902500Y676000D03*
G54D55*
X488838Y137225D03*
G54D56*
Y164744D03*
G54D50*
X90157Y413583D03*
X309055Y157677D03*
G54D45*
X309252Y413583D03*
G54D57*
X652756Y180000D03*
G54D46*
X89764Y238386D03*
G54D58*
X865353Y332598D03*
G54D51*
X163189Y669291D03*
G54D48*
X70866Y98425D03*
Y472441D03*
X314961D03*
X405512Y39370D03*
X364173Y740157D03*
X612205Y433071D03*
Y740157D03*
X875984Y433071D03*
X875985Y740157D03*
G54D49*
X49213D03*
X875985Y59055D03*
G54D12*
X56102Y24606D03*
X103346Y34449D03*
X590300Y574400D03*
G54D26*
X339331Y49803D03*
X360669Y91929D03*
G54D14*
X38590Y55260D03*
X30270Y48330D03*
X31100Y458733D03*
X26576Y457406D03*
X41250Y494600D03*
X53524Y521269D03*
Y526995D03*
X75405Y521695D03*
X69778D03*
X64151D03*
X49600Y496050D03*
X55300Y495600D03*
X62276Y550493D03*
X74151Y545516D03*
X74498Y551757D03*
X71002Y539219D03*
X74076Y535966D03*
X75508Y542198D03*
X71002Y542368D03*
X67852Y539219D03*
X71002Y545518D03*
Y558117D03*
X74152Y567565D03*
X71002D03*
Y564396D03*
X74152Y580163D03*
Y577013D03*
X71002Y561266D03*
X67853Y564416D03*
X75066Y563235D03*
X71002Y554967D03*
X67853D03*
X78276Y545566D03*
X67853Y542368D03*
X71002Y548668D03*
X52408Y543876D03*
X64701Y542366D03*
X52603Y549526D03*
X52485Y555153D03*
X53300Y560879D03*
X67853Y570715D03*
X74152Y583312D03*
X64703Y586463D03*
X63456Y555041D03*
X64701Y567566D03*
Y561266D03*
X67853D03*
Y577015D03*
X53524Y532622D03*
X52613Y538242D03*
X53302Y567317D03*
X59200Y582200D03*
X38550Y617950D03*
X47150Y665500D03*
X76100Y697100D03*
X97600Y54810D03*
X89070Y62600D03*
X114390Y453185D03*
X102250Y455000D03*
X108300Y435900D03*
X118108Y453159D03*
X121826Y453156D03*
X128968Y452741D03*
X125353Y452385D03*
X132109Y451199D03*
X136021Y451394D03*
X127812Y445066D03*
X117200Y495200D03*
X105920Y477098D03*
X141980Y508590D03*
X97637Y492891D03*
X118900Y522000D03*
X138000Y485900D03*
X102700Y507100D03*
X116500Y477000D03*
X144500Y489500D03*
X92286Y521695D03*
X81032D03*
X86659D03*
X97913D03*
X114500Y490000D03*
X101800Y493000D03*
X137050Y476346D03*
X132774Y497000D03*
X86750Y542368D03*
X126337Y554085D03*
X130311Y546700D03*
X81276Y548766D03*
X119605Y548705D03*
X86750Y539218D03*
X83600Y545518D03*
X89899D03*
X127300Y543200D03*
X89899Y539218D03*
X117200Y546300D03*
X83600Y539219D03*
X86750Y545518D03*
X122600Y557480D03*
X86750Y554965D03*
X130607Y569636D03*
X86750Y558115D03*
X126347Y569556D03*
X83600Y551817D03*
X117400Y567650D03*
X83600Y573865D03*
X86750Y586463D03*
Y583313D03*
X83601Y580164D03*
X89899Y577014D03*
X86750D03*
X83600Y564415D03*
X86750D03*
X83600Y561265D03*
X96570Y581730D03*
X86750Y551815D03*
X123300Y530300D03*
X133800Y528500D03*
X123200Y534600D03*
X143500Y529000D03*
X93744Y542019D03*
X133554Y537374D03*
X93051Y587466D03*
X83600Y567565D03*
X93049Y573864D03*
X89899Y567565D03*
X93048Y580164D03*
X89899Y561265D03*
X86750D03*
X94720Y557158D03*
X92600Y535623D03*
X96371Y534124D03*
X123370Y606700D03*
X119600D03*
X118500Y638100D03*
X140700Y657700D03*
X130800Y656100D03*
X127401Y606930D03*
X123500Y613100D03*
X93053Y606734D03*
X142447Y611714D03*
X119000Y633200D03*
X120500Y651800D03*
X134650Y612900D03*
X144750Y606350D03*
X141971Y624700D03*
X98200Y616900D03*
X129800Y630700D03*
X105600Y597000D03*
X105400Y601300D03*
X104600Y609900D03*
X105600Y605900D03*
X104600Y614000D03*
X104500Y618800D03*
X117050Y602000D03*
X116200Y611600D03*
X116023Y607423D03*
X119400Y614100D03*
X116500Y621000D03*
X116400Y616900D03*
X130800Y606700D03*
X138500Y637900D03*
X130500Y638600D03*
X134700D03*
X129903Y634500D03*
X107100Y679600D03*
X106879Y707245D03*
X125376Y701124D03*
X106355Y710745D03*
X106635Y701465D03*
X87683Y698924D03*
X84600Y688000D03*
X119849Y709715D03*
X186602Y459767D03*
X197085Y459899D03*
X190278Y459865D03*
X193686Y459799D03*
X176000Y460200D03*
X172200Y460100D03*
X157496Y461248D03*
X166600Y509800D03*
X166700Y499800D03*
X208370Y491570D03*
X183100Y499800D03*
X170838Y481762D03*
X146300Y502600D03*
X146112Y509412D03*
X158100Y493000D03*
X158400Y513600D03*
X155001Y513707D03*
X182874Y513591D03*
X178869Y513593D03*
X174900Y499800D03*
X166600Y513600D03*
X170700D03*
X172370Y463798D03*
X187000Y468000D03*
X146293Y464338D03*
X146193Y476938D03*
X146293Y472738D03*
X186600Y477700D03*
X187000Y499500D03*
X146500Y492500D03*
X183300Y493100D03*
X145400Y524046D03*
X176100Y473200D03*
X174700Y513900D03*
X182300Y509600D03*
X184780Y526990D03*
X187167Y513167D03*
X191100Y513367D03*
X154500Y487000D03*
X178869Y509793D03*
X209800Y478500D03*
X205447Y487762D03*
X158290Y502380D03*
X182874Y523590D03*
X205516Y467968D03*
X170700Y509800D03*
X170900Y500000D03*
X165900Y524100D03*
X209256Y467946D03*
X172100Y467300D03*
X176800Y492200D03*
X175805Y524073D03*
X206180Y509524D03*
X191100Y526000D03*
X195149Y513751D03*
X150500Y493000D03*
X190950Y482100D03*
X196200Y482600D03*
X200100Y491700D03*
X146216Y486045D03*
X196243Y486782D03*
X159480Y506590D03*
X155540Y506510D03*
X195300Y498900D03*
X195379Y510158D03*
X150162Y525937D03*
X148527Y519491D03*
X191725Y523074D03*
X148409Y575672D03*
X144876Y590854D03*
X148409Y579353D03*
X144876Y587173D03*
X175100Y529100D03*
X203610Y529397D03*
X168390Y532060D03*
X184830Y529960D03*
X149419Y535654D03*
X191200Y529400D03*
X199400D03*
X208000Y529300D03*
X149242Y531080D03*
X152584Y532922D03*
X152415Y540014D03*
X194490Y645390D03*
X191370Y608190D03*
X208700Y625149D03*
X200879Y614739D03*
X145900Y641300D03*
X164800Y640200D03*
X173000Y640400D03*
X193610Y640040D03*
X189500Y639700D03*
X178140Y630330D03*
X196249Y630091D03*
X199400Y628646D03*
X151550Y629800D03*
X163200Y610070D03*
X160420Y610170D03*
X184050Y629500D03*
X181176Y627600D03*
X209093Y615849D03*
X166690Y615060D03*
X166600Y617850D03*
X195900Y649350D03*
X203400Y649600D03*
X146800Y629900D03*
X180700Y640460D03*
X204800Y617440D03*
X204642Y621140D03*
X177300Y626800D03*
X204150Y645180D03*
X199600Y650100D03*
X192960Y628510D03*
X187900Y628500D03*
X152700Y640800D03*
X161000Y634300D03*
X157200Y634200D03*
X206700Y695400D03*
X162100Y711215D03*
X151949Y691715D03*
X175233Y704382D03*
X163349Y702715D03*
X150849Y710215D03*
X163260Y706988D03*
X169070Y696220D03*
X159519Y694455D03*
X193500Y663000D03*
X200400Y694700D03*
X196900Y661350D03*
X206300Y661100D03*
X181300Y679100D03*
X185100Y705600D03*
X184800Y709300D03*
X190200Y671000D03*
X187500Y673100D03*
X272000Y461800D03*
X268350Y461950D03*
X275100Y460300D03*
X259000Y453900D03*
X251700Y443600D03*
X268900Y445150D03*
X244700Y451200D03*
X236100Y445100D03*
X239300Y443800D03*
X243000D03*
X247900Y445300D03*
X260600Y442600D03*
X250500Y451300D03*
X224500Y445600D03*
X254900Y453900D03*
X232200Y445600D03*
X275700Y490300D03*
X244900Y527300D03*
X228150Y525750D03*
X275400Y470300D03*
X213100Y476300D03*
X261200Y525400D03*
X242500Y523500D03*
X254500Y509600D03*
X213100Y472900D03*
X275200Y474500D03*
X258100Y516400D03*
X227500Y512200D03*
X265148Y524595D03*
X228700Y490717D03*
X230700Y486658D03*
X249050Y527150D03*
X249640Y495080D03*
X234700Y490900D03*
X258381Y509498D03*
X225914Y523051D03*
X231800Y512100D03*
X223600Y512400D03*
X213359Y480489D03*
X238400Y511300D03*
X265274Y509512D03*
X267800Y479900D03*
X245743Y546963D03*
X270021Y549394D03*
X257000Y548400D03*
X263216Y554697D03*
X254530Y564300D03*
X251446Y553754D03*
X254500Y579500D03*
X273500Y567400D03*
X254300Y586500D03*
X273400Y590902D03*
X231434Y562844D03*
X234300Y582300D03*
X231200Y576800D03*
X231000Y571900D03*
X257300Y537500D03*
X214900Y529400D03*
X234943Y565199D03*
X254600Y567700D03*
X260731Y561264D03*
X260741Y542700D03*
X264333Y528926D03*
X254905Y555761D03*
X258528Y555161D03*
X259100Y567706D03*
X257000Y571700D03*
X223900Y531200D03*
X228100Y545500D03*
X228800Y542100D03*
X228313Y552169D03*
X262000Y586900D03*
X257851Y580080D03*
X270145Y557526D03*
X261308Y583388D03*
X237100Y590000D03*
X257700Y586400D03*
X261500Y576400D03*
X261600Y580000D03*
X257891Y563786D03*
X257600Y576500D03*
X233607Y557671D03*
X254500Y575070D03*
X261100Y571600D03*
X234800Y572000D03*
X232400Y533200D03*
X248900Y545700D03*
X267957Y537304D03*
X274623Y578896D03*
X271357Y537253D03*
X233036Y550942D03*
X213800Y631200D03*
X212308Y605949D03*
X229796Y610104D03*
X270000Y602400D03*
X222950Y647900D03*
X255570Y616631D03*
X258962Y616384D03*
X236000Y647400D03*
X225900Y630700D03*
X231500Y659100D03*
X228149Y600094D03*
X242710Y604620D03*
X226471Y649129D03*
X243322Y597509D03*
X251314Y598106D03*
X251338Y601506D03*
X258550Y606527D03*
Y610096D03*
X215606Y645806D03*
X229500Y631500D03*
X212900Y619201D03*
X273714Y629870D03*
X266571Y630071D03*
X245100Y647200D03*
X272200Y648550D03*
X221238Y620524D03*
X234205Y598743D03*
X233258Y595693D03*
X232130Y612950D03*
X251900Y609600D03*
X259777Y638873D03*
X242000Y656400D03*
X255733Y622329D03*
X253196Y706062D03*
X255050Y675750D03*
X254800Y689400D03*
X269200Y699600D03*
X258423Y711343D03*
X268520Y719420D03*
X270900Y667200D03*
X237509Y674915D03*
X266200Y679400D03*
X268384Y662909D03*
X263700Y723500D03*
X264700Y700000D03*
X214270Y695095D03*
X275300Y668749D03*
X217638Y695562D03*
X235000Y692900D03*
X262323Y716917D03*
X255200Y680950D03*
X239400Y677900D03*
X266300Y692574D03*
X254648Y745463D03*
X311715Y20397D03*
X310353Y62159D03*
X326553Y34687D03*
X339232Y113960D03*
X338743Y122894D03*
X305700Y197600D03*
X295841Y176793D03*
X323582Y179064D03*
X299107Y177740D03*
X295462Y173414D03*
X304231Y265048D03*
X335000Y226992D03*
X305782Y230874D03*
X335082Y231574D03*
X322301Y220009D03*
X305782Y217274D03*
X305682Y224074D03*
X305782Y220674D03*
X305454Y244461D03*
X334998Y255520D03*
X305373Y251101D03*
X334998Y259033D03*
X306412Y254339D03*
X335060Y262516D03*
X305882Y234274D03*
X305772Y237673D03*
X321700Y246000D03*
X321600Y250000D03*
X305781Y241076D03*
X334582Y287284D03*
Y283784D03*
X307567Y331592D03*
Y328092D03*
X304267Y318892D03*
Y315392D03*
X307567Y306292D03*
Y302792D03*
X304267Y293692D03*
Y290192D03*
X328182Y325174D03*
Y321674D03*
X334582Y312574D03*
Y309074D03*
X328182Y299977D03*
Y296477D03*
X307567Y281092D03*
Y277592D03*
X304231Y268548D03*
X328913Y274414D03*
X334017Y272000D03*
X337808Y288709D03*
X304267Y369292D03*
Y365792D03*
X307567Y356692D03*
Y353192D03*
X304267Y344092D03*
Y340592D03*
X328182Y375518D03*
Y372018D03*
X334582Y362974D03*
Y359474D03*
Y337771D03*
Y334271D03*
X328182Y350371D03*
Y346871D03*
X334000Y382700D03*
X303680Y380972D03*
X316900Y384100D03*
X319679Y387121D03*
X314000Y390500D03*
X335800Y379800D03*
X338800Y435100D03*
X281200Y453500D03*
X333850Y458400D03*
X286700Y457500D03*
X323759Y435145D03*
X327159Y435201D03*
X276634Y498311D03*
X325136Y519316D03*
X333922Y527323D03*
X340961Y511600D03*
X298335Y521458D03*
X304800Y512800D03*
X286797Y516522D03*
X308687Y519193D03*
X302307Y505799D03*
X298907Y505851D03*
X292100Y516000D03*
X297400Y517981D03*
X336600Y504500D03*
X336800Y499967D03*
X325400Y505800D03*
X282403Y474500D03*
X282400Y470200D03*
X328200Y511600D03*
X331200Y508900D03*
X299448Y511300D03*
X277603Y479948D03*
X332821Y515415D03*
X278400Y463300D03*
X280939Y504705D03*
X314400Y505750D03*
X334650Y508900D03*
X300476Y546907D03*
X325774Y547428D03*
X331700Y587896D03*
X303520Y550085D03*
X296835Y591015D03*
X280646Y557150D03*
X303500Y582200D03*
X333847Y531105D03*
X286195Y530579D03*
X291800Y576708D03*
X333800Y534830D03*
X329840Y572710D03*
X337550Y534619D03*
X295824Y578108D03*
X325475Y572818D03*
X323659Y557310D03*
X334900Y586100D03*
X333512Y553888D03*
X281610Y590260D03*
X324200Y565300D03*
X281490Y586862D03*
X337300Y583000D03*
X336367Y549943D03*
X294107Y560762D03*
X330729Y557268D03*
X298000Y561000D03*
X327059Y557247D03*
X288309Y566467D03*
X328580Y568120D03*
X291000Y570810D03*
X320954Y572631D03*
X277048Y590470D03*
X319529Y562413D03*
X319252Y566509D03*
X285912Y538750D03*
X318736Y549697D03*
X280100Y532100D03*
X322889Y529380D03*
X322843Y533254D03*
X279664Y535473D03*
X328771Y549035D03*
X332808Y547575D03*
X332834Y543993D03*
X337346Y545100D03*
X341316Y545000D03*
X282000Y583500D03*
X298514Y550184D03*
X293087Y530571D03*
X325687Y551368D03*
X319430Y557486D03*
X276839Y582309D03*
X277441Y539882D03*
X308200Y593153D03*
X310292Y532128D03*
X278443Y648857D03*
X284495Y613130D03*
X286700Y622190D03*
X340100Y631417D03*
X339751Y616882D03*
Y613185D03*
X335036Y603039D03*
X338733D03*
X325300Y648700D03*
X294500Y630600D03*
X298100Y630650D03*
X330400Y644300D03*
X334700Y644500D03*
X302459Y599531D03*
X306100Y599500D03*
X306231Y602898D03*
X302180Y603084D03*
X335100Y650600D03*
X338100Y635800D03*
X331718Y655832D03*
X329100Y650700D03*
X317689Y599833D03*
X287200Y632600D03*
X290900Y630900D03*
X278769Y700697D03*
X321800Y678500D03*
X281000Y678000D03*
X304400Y665100D03*
X316465Y716063D03*
X340500Y711750D03*
X335750Y664700D03*
X288700Y667900D03*
X340100Y718200D03*
X327250Y701500D03*
X327162Y696776D03*
X282300Y700100D03*
X316000Y671850D03*
X276800Y697925D03*
X338669Y691580D03*
X339804Y679030D03*
X340403Y699400D03*
X340300Y703100D03*
X336200Y677000D03*
X289700Y678830D03*
X280646Y717540D03*
X276100Y677700D03*
X300100Y670300D03*
X304700Y668500D03*
X291700Y737000D03*
X287620Y737300D03*
X290000Y727000D03*
X313873Y735907D03*
X314100Y739300D03*
X370870Y45605D03*
X368059Y57759D03*
X354798Y22452D03*
X386759Y79693D03*
X390456D03*
X342539Y120370D03*
X369253Y88733D03*
X367287Y77118D03*
X381269Y94981D03*
X384666Y93741D03*
X349206Y129948D03*
X390964Y87226D03*
X388700Y89800D03*
X370149Y167337D03*
X370882Y163688D03*
X387202Y164664D03*
X387393Y160859D03*
X404727Y162141D03*
X392102Y175384D03*
X400205Y158209D03*
Y161906D03*
X392458Y171676D03*
X400430Y147190D03*
X361792Y243154D03*
X372888Y208022D03*
X359882Y203458D03*
X347482Y254774D03*
X341882Y251064D03*
X342885Y276301D03*
X342958Y279701D03*
X383170Y329807D03*
X345582Y380874D03*
X344732Y393882D03*
Y390274D03*
X383285Y347114D03*
X383327Y343379D03*
X396561Y351418D03*
X346600Y375000D03*
X344732Y386874D03*
X365100Y348300D03*
X372491Y378025D03*
X365200Y344400D03*
X378492Y378175D03*
X383030Y352442D03*
X367358Y372531D03*
X367471Y369120D03*
X360100Y453500D03*
X342700Y435200D03*
X350491Y453809D03*
X372000Y452100D03*
X369900Y458700D03*
X387450Y454558D03*
X387396Y458126D03*
X384395Y449114D03*
X374700Y460300D03*
X350400Y459000D03*
X381106Y441241D03*
X350400Y462400D03*
X374650Y456771D03*
X346500Y435200D03*
X364500Y453700D03*
X367400Y461200D03*
X355400Y453800D03*
X357900Y450800D03*
X357450Y491450D03*
X364500Y525260D03*
X369300Y508700D03*
X344400Y505400D03*
X344500Y500300D03*
X363500Y464700D03*
X372000Y477710D03*
X355300Y502700D03*
X357700Y499000D03*
X400080Y500854D03*
X384849Y525499D03*
Y521681D03*
X355300Y506100D03*
Y513500D03*
X386367Y474700D03*
X400080Y519500D03*
Y491107D03*
Y523903D03*
Y528243D03*
X389349Y480100D03*
X381986Y515631D03*
X374751Y485636D03*
X374715Y498722D03*
X366950Y464700D03*
X390229Y508189D03*
X341500Y520400D03*
X373699Y521160D03*
X359100Y503200D03*
X374800Y516912D03*
X387450Y467000D03*
X389288Y483500D03*
X358800Y478000D03*
X373800Y503000D03*
X370900Y464700D03*
X378267Y496100D03*
X349088Y500296D03*
X384950Y560496D03*
X383000Y577000D03*
X386305Y581647D03*
X362700Y551200D03*
X361279Y581647D03*
X362100Y574700D03*
X349000Y581360D03*
X379050Y539931D03*
X341740Y535800D03*
X352279Y580294D03*
X346303Y591947D03*
X386723Y544565D03*
X342440Y571770D03*
X361900Y570800D03*
X369500Y542900D03*
X388641Y549747D03*
X400093Y536351D03*
X399726Y562327D03*
X399946Y558677D03*
X344163Y553395D03*
X345259Y557566D03*
X391993Y582154D03*
X362300Y555200D03*
X343840Y566440D03*
X348300Y565400D03*
X364900Y585171D03*
X364964Y588771D03*
X372939Y559838D03*
X346590Y572090D03*
X350278Y572306D03*
X366270Y563400D03*
X373222Y535938D03*
X370247Y546218D03*
X370223Y549965D03*
X384950Y551876D03*
Y555276D03*
X383056Y563675D03*
X400060Y554743D03*
X393912Y571899D03*
X393910Y575305D03*
X341493Y541250D03*
X393912Y578705D03*
X348000Y612661D03*
X352720Y600970D03*
X367133Y596067D03*
X382380Y612277D03*
X352400Y626102D03*
X372408Y629626D03*
X364014Y593996D03*
X343797Y631417D03*
X381967Y616123D03*
X361227Y630300D03*
X377700Y595000D03*
X383199Y623168D03*
X382438Y608755D03*
X384158Y638105D03*
X380443D03*
X400064Y652598D03*
X384300Y619925D03*
X384220Y700618D03*
X367600Y696800D03*
X396166Y692630D03*
X343200Y667600D03*
X389999Y664697D03*
X367700Y685450D03*
X343338Y679236D03*
X399999Y673422D03*
X396419Y679708D03*
X398983Y706749D03*
X382308Y665022D03*
X396419Y686586D03*
X372350Y698400D03*
X399093Y703350D03*
X380300Y703000D03*
X399154Y699950D03*
X341900Y690350D03*
X346600Y714500D03*
X346000Y684300D03*
X383800Y688400D03*
X380387Y685261D03*
X392500Y673500D03*
X392800Y677600D03*
X341934Y662794D03*
X378595Y664960D03*
X388626Y715509D03*
X392500Y692500D03*
X355298Y711750D03*
X396419Y683186D03*
X469058Y49156D03*
X439200Y22100D03*
X439549Y26339D03*
X439554Y30429D03*
X439302Y34040D03*
X458972Y49634D03*
X462625Y49881D03*
X467300Y20000D03*
X450454Y38147D03*
X448520Y49979D03*
X430800Y22200D03*
X433600Y19900D03*
X428001Y25269D03*
X433400Y63373D03*
X438600Y91033D03*
X419662Y71426D03*
X423340Y71621D03*
X469901Y94047D03*
X415211Y71263D03*
X461736Y111300D03*
X442800Y90934D03*
X512806Y49494D03*
X473151Y50052D03*
X521200Y57600D03*
X496035Y46435D03*
X503814Y56676D03*
X515500Y57900D03*
X486568Y38006D03*
X486114Y41700D03*
X496430Y22890D03*
X491270Y18877D03*
X485674Y32924D03*
X524950Y16120D03*
X473172Y95508D03*
X479147Y102165D03*
X490100Y111300D03*
X486400Y74700D03*
X481800Y71200D03*
X513909Y85849D03*
X510408Y85779D03*
X599422Y51662D03*
X568430Y50010D03*
X596489Y14110D03*
X559600Y47600D03*
X575550Y42800D03*
X601311Y13521D03*
X569300Y66274D03*
X545200Y69000D03*
X596300Y66950D03*
X549550Y61900D03*
X597950Y58950D03*
X564500Y64100D03*
X573600Y49750D03*
X584550Y80750D03*
X559900Y88400D03*
X563268Y88872D03*
X540179Y111036D03*
X539346Y114333D03*
X578900Y82500D03*
X551500Y82400D03*
X599682Y103715D03*
X547100Y79900D03*
X578400Y74500D03*
X562160Y178600D03*
X598964Y354128D03*
X596077Y369579D03*
X602075Y339970D03*
X586155Y393023D03*
X593064Y400910D03*
X593229Y397308D03*
X666535Y26149D03*
X665800Y7550D03*
X666400Y22200D03*
X619980Y197550D03*
X634000Y187500D03*
X630800Y147600D03*
X634800Y147700D03*
X644100Y203350D03*
X634450Y252100D03*
X631550Y249850D03*
X625926Y247530D03*
X627200Y253550D03*
X625250Y264250D03*
X625550Y244150D03*
Y240750D03*
X645516Y225334D03*
X620750Y258050D03*
X642547Y226992D03*
X632958Y231000D03*
X633109Y234397D03*
X632900Y238000D03*
X628300Y230550D03*
X625700Y235750D03*
X640141Y259859D03*
X640400Y217600D03*
X636491Y217592D03*
X633092Y217496D03*
X659500Y205300D03*
X665500Y201900D03*
X662900Y205300D03*
X645400Y264050D03*
X620160Y203500D03*
X660700Y292200D03*
X634830Y292095D03*
X638453Y291949D03*
X633400Y274600D03*
X657500Y281500D03*
X652850Y269600D03*
X642300Y276450D03*
X649000Y273500D03*
X652100Y279300D03*
X648000Y281300D03*
X656700Y305607D03*
X664600Y306100D03*
X648700Y303600D03*
X652500Y305707D03*
X638603Y296320D03*
X642003Y296249D03*
X645403Y296229D03*
X631069Y292512D03*
X654600Y367600D03*
X639318Y354003D03*
X643082Y353941D03*
X629239Y387969D03*
X620100Y384100D03*
X608600Y362600D03*
X659300Y373100D03*
X637000Y373856D03*
X632220Y389694D03*
X607800Y382362D03*
X607100Y351200D03*
X638360Y383805D03*
X642270Y383869D03*
X605400Y393400D03*
X618600Y364375D03*
X609240Y370337D03*
X616900Y343000D03*
X615150Y364200D03*
X640968Y370425D03*
X606626Y354723D03*
X637353Y379591D03*
X636963Y405999D03*
X632180Y397968D03*
X654300Y504100D03*
X613000Y463000D03*
X666216Y470684D03*
X632800Y561600D03*
X620160Y544793D03*
X635970Y557600D03*
X638660Y568043D03*
X616160Y542700D03*
X614000Y561250D03*
X606600Y551100D03*
X677770Y196410D03*
X730550Y179050D03*
X732000Y185900D03*
X716650Y174400D03*
X674300Y198900D03*
X718121Y256326D03*
X718089Y246834D03*
X718098Y259423D03*
X718072Y265748D03*
X718089Y249984D03*
X718129Y253144D03*
X693800Y264300D03*
X725466Y200819D03*
X707923Y219765D03*
X708900Y214500D03*
X718111Y224802D03*
X706500Y212150D03*
X709615Y223228D03*
X718111Y231101D03*
X696300Y215750D03*
X702900Y212350D03*
X707679Y233664D03*
X718111Y227952D03*
X722322Y200935D03*
X704279Y226664D03*
X705529Y231064D03*
X705779Y236764D03*
X706079Y240664D03*
X710716Y235827D03*
X714945Y234230D03*
X726988Y204312D03*
X718123Y201101D03*
X710079Y203664D03*
X718895Y207125D03*
X705364Y205864D03*
X713168Y207689D03*
X718111Y221653D03*
X733859Y215355D03*
X718110Y234252D03*
X709679Y239164D03*
X727560Y215355D03*
X716116Y207469D03*
X718111Y237401D03*
X709079Y229564D03*
X703979Y219995D03*
X718111Y240550D03*
X711812Y243700D03*
X714961D03*
X730709Y215355D03*
X724410D03*
X732264Y204312D03*
X703320Y203900D03*
X733859Y212206D03*
X729800Y208400D03*
X730709Y221654D03*
X733858D03*
X724410D03*
Y234252D03*
Y240551D03*
Y246850D03*
Y253150D03*
Y227953D03*
Y265748D03*
Y259449D03*
X704579Y261964D03*
X682030Y253630D03*
X706100Y250000D03*
X690600Y230700D03*
X691243Y211743D03*
X692600Y201300D03*
X677800Y215900D03*
X706796Y295829D03*
X726895Y309117D03*
X711799Y304234D03*
X713339Y306954D03*
X724063Y306305D03*
X698039Y285854D03*
X707834Y293060D03*
X707079Y286964D03*
X704079Y300964D03*
X719200Y307400D03*
X705579Y298464D03*
X695508Y288964D03*
X710679Y267894D03*
X721230Y284653D03*
X718099Y290964D03*
X710329Y285214D03*
X718117Y281465D03*
X718080Y284653D03*
X701708Y292364D03*
X706277Y279162D03*
X718072Y278346D03*
X708409Y276771D03*
X733892Y297246D03*
X730708Y297243D03*
X714619Y303884D03*
X692750Y293200D03*
X718109Y272034D03*
X694307Y283485D03*
X722468Y308964D03*
X727558Y297243D03*
X733859Y272048D03*
X690579Y299964D03*
X675555Y318736D03*
X672350Y317600D03*
X724409Y297243D03*
X700323Y283078D03*
X716300Y331340D03*
X733859Y284646D03*
X695300Y306700D03*
X718099Y287814D03*
X712410Y331320D03*
X702250Y329650D03*
X733857Y290944D03*
X727558D03*
X730300Y314900D03*
X724410Y272047D03*
Y278346D03*
Y284645D03*
X669950Y310950D03*
X681800Y287950D03*
X718137Y275186D03*
X702939Y281484D03*
X718109Y268934D03*
X714949Y287814D03*
X718300Y362900D03*
X722500Y353000D03*
X718000D03*
X713500Y362900D03*
X729900Y393200D03*
X709006Y410206D03*
X721504Y402321D03*
X699900Y453600D03*
X691813Y407210D03*
X691874Y410741D03*
X691873Y403800D03*
X690550Y453850D03*
X690300Y460200D03*
X720900Y412900D03*
X696800Y476400D03*
X689100Y507900D03*
X730600Y493100D03*
X716078Y492334D03*
X672500Y507100D03*
X696000Y508400D03*
X715391Y479109D03*
X725000Y576100D03*
X714800Y567956D03*
X710000Y549100D03*
X710100Y545600D03*
X705176Y593429D03*
X717450Y551554D03*
X697200Y529200D03*
X705676Y562429D03*
X702515Y597064D03*
X693900Y597800D03*
X703800Y608400D03*
X712708Y603038D03*
X723369Y599835D03*
X722122Y611840D03*
X769812Y53660D03*
X756431Y54010D03*
X736803Y52087D03*
X779400Y54750D03*
X746500Y47200D03*
X780815Y47062D03*
X776600Y35250D03*
X762765Y42200D03*
X781250Y101750D03*
X779594Y126865D03*
X762000Y113000D03*
X763825Y89975D03*
X776500Y82700D03*
X750500Y118500D03*
X750600Y114200D03*
X769500Y91000D03*
X792600Y101300D03*
X772800Y107550D03*
X776850Y115050D03*
X738160Y199480D03*
X749900Y185200D03*
X786343Y179959D03*
X745700Y185900D03*
X769100Y187800D03*
X786388Y183429D03*
X772810Y179901D03*
X772700Y183300D03*
X737000Y185900D03*
X765900Y191900D03*
X768579Y203964D03*
X764900Y207200D03*
X761600Y207300D03*
X787402Y240552D03*
Y243701D03*
X793700Y256262D03*
X752759Y218499D03*
X755909Y218514D03*
X790550Y253150D03*
X799972Y256309D03*
X781080Y265763D03*
X784258Y262618D03*
X777967Y262576D03*
X790523Y256289D03*
X800021Y243717D03*
X795593Y206063D03*
X777953Y256300D03*
X781300Y207800D03*
X774803Y265749D03*
X737009Y240552D03*
X746457Y215355D03*
X737029Y215337D03*
X743279Y215364D03*
X740158Y215355D03*
X743279Y212196D03*
X741294Y208274D03*
X743008Y206059D03*
X765355Y240552D03*
X743307Y246850D03*
X762217Y240526D03*
X755880Y240563D03*
X749580D03*
X755869Y253149D03*
X762167Y246850D03*
X755907Y246851D03*
X749569Y246850D03*
X762168Y253149D03*
X749608Y253150D03*
X743282Y253161D03*
X755868Y265748D03*
X755882Y259461D03*
X762218Y259425D03*
X749582Y259461D03*
X743282D03*
X762181Y265762D03*
X749582Y265761D03*
X743282D03*
X743281Y240562D03*
X768480Y265762D03*
X768518Y259425D03*
X768467Y253149D03*
Y246850D03*
X771653Y246887D03*
X762205Y221654D03*
X784252D03*
X777953D03*
X790551D03*
X740158D03*
X755906D03*
X746457D03*
X793701Y234254D03*
X781127Y246863D03*
X793672Y240560D03*
X796821Y246859D03*
X793701Y227954D03*
X796850Y221654D03*
X793674Y265758D03*
X793699Y262634D03*
X768504Y215355D03*
X763963Y331837D03*
X766437Y329363D03*
X748737Y330263D03*
X740157Y297243D03*
X737008Y297244D03*
X740158Y284646D03*
X744881Y309000D03*
X743306Y297243D03*
X790526Y300406D03*
X765369Y281474D03*
X771669D03*
X781120Y284665D03*
X759070Y281514D03*
X749816Y303716D03*
X777790Y304778D03*
X769768Y304464D03*
X759208Y304284D03*
X784252Y268885D03*
X796839Y290934D03*
X787438Y275197D03*
X796832Y272064D03*
X796875Y304331D03*
X796862Y281522D03*
X784249Y281464D03*
X787426Y272060D03*
X790551Y278384D03*
X743308Y284646D03*
X746457D03*
X737009D03*
X744400Y322800D03*
X746456Y297243D03*
X765353Y287794D03*
X771653D03*
X777952D03*
X784251D03*
X762225Y297227D03*
X755898Y287804D03*
X743283Y272060D03*
X755882D03*
X749581D03*
X746456Y290944D03*
X740157D03*
X793700Y297243D03*
X796849D03*
X790545Y290959D03*
X793694D03*
X793703Y287797D03*
X796839Y287784D03*
X793675Y284637D03*
X793679Y281508D03*
X793675Y278357D03*
X796868Y278364D03*
X793737Y275196D03*
X793682Y272064D03*
X793683Y268879D03*
X796850Y268910D03*
X763081Y350437D03*
X765555Y347963D03*
X775181Y338437D03*
X777655Y335963D03*
X780263Y350737D03*
X782737Y348263D03*
X792163Y338937D03*
X794637Y336463D03*
X746263Y332737D03*
X752363Y343737D03*
X754837Y341263D03*
X790357Y377781D03*
X735300Y401957D03*
X774700Y483600D03*
X782000Y505600D03*
X771184Y514916D03*
X745700Y498250D03*
X742300Y498200D03*
X759000Y482900D03*
X759169Y497414D03*
X750600Y497400D03*
X759200Y508000D03*
X777600Y512200D03*
X781700Y510900D03*
X736600Y500000D03*
X780750Y496750D03*
X781050Y492550D03*
X753099Y530282D03*
X795922Y531500D03*
X747200Y611900D03*
X802786Y57150D03*
X841300Y54200D03*
X818785Y50692D03*
X803000Y117100D03*
X813349Y73142D03*
X809349Y73197D03*
X821962Y189277D03*
X801385Y183067D03*
X801340Y179597D03*
X831504Y199129D03*
X840591Y264609D03*
X834791Y258109D03*
X831609Y261291D03*
X834127Y248490D03*
X830945Y251672D03*
X832148Y204444D03*
X816900Y231700D03*
X803160Y259454D03*
X803150Y256336D03*
X807177Y261023D03*
X814262Y218950D03*
X810277Y243190D03*
X810688Y238944D03*
X803129Y240535D03*
X803158Y237414D03*
X806862Y243302D03*
X806918Y237804D03*
X826000Y233400D03*
X828000Y243100D03*
X851591Y310409D03*
X848409Y313591D03*
X856091Y294909D03*
X852909Y298091D03*
X850091Y288909D03*
X846909Y292091D03*
X846591Y270409D03*
X843409Y273591D03*
X844591Y283409D03*
X841409Y286591D03*
X837409Y267791D03*
X822817Y331022D03*
X810079Y271264D03*
X809968Y290464D03*
X808400Y300900D03*
X812164Y279674D03*
X811600Y317300D03*
X802363Y336637D03*
X804837Y334163D03*
X820343Y333496D03*
X817700Y385700D03*
X806400Y398700D03*
X810100Y404934D03*
X857000Y410600D03*
X850950Y489300D03*
X804584Y526584D03*
X829500Y481500D03*
X883240Y301973D03*
X888668Y322100D03*
X886540Y388996D03*
G54D32*
X468000Y35400D03*
X464000Y35500D03*
X468000Y39500D03*
Y31500D03*
X472000Y35500D03*
G54D25*
X201801Y684252D03*
X225601D03*
G54D39*
X651575Y20039D03*
X608267D03*
X641732Y126811D03*
X624015D03*
X651575Y72441D03*
X608267D03*
X730315Y20039D03*
X687007D03*
X720472Y126811D03*
X702755D03*
X730315Y72441D03*
X687007D03*
G54D33*
X421653Y130709D03*
X428740Y125985D03*
X435827Y130709D03*
X442913Y125985D03*
X450000Y130709D03*
X457086Y125985D03*
X464173Y130709D03*
X471260Y125985D03*
X428740Y131496D03*
X442913D03*
X457086D03*
X471260D03*
X421653Y136221D03*
X435827D03*
X450000D03*
X464173D03*
X421653Y144882D03*
X428740Y140158D03*
X435827Y144882D03*
X442913Y140158D03*
X450000Y144882D03*
X457086Y140158D03*
X464173Y144882D03*
X471260Y140158D03*
X421653Y150394D03*
X428740Y145670D03*
X435827Y150394D03*
X442913Y145670D03*
X450000Y150394D03*
X457086Y145670D03*
X464173Y150394D03*
X471260Y145670D03*
X421653Y159055D03*
X428740Y154331D03*
X435827Y159055D03*
X442913Y154331D03*
X450000Y159055D03*
X457086Y154331D03*
X464173Y159055D03*
X471260Y154331D03*
X421653Y164567D03*
X428740Y159843D03*
X435827Y164567D03*
X442913Y159843D03*
X450000Y164567D03*
X457086Y159843D03*
X464173Y164567D03*
X471260Y159843D03*
X421653Y173229D03*
X428740Y168504D03*
X435827Y173229D03*
X442913Y168504D03*
X450000Y173229D03*
X457086Y168504D03*
X464173Y173229D03*
X471260Y168504D03*
X421653Y178740D03*
X428740Y174016D03*
X435827Y178740D03*
X442913Y174016D03*
X450000Y178740D03*
X457086Y174016D03*
X464173Y178740D03*
X471260Y174016D03*
X506693Y130709D03*
X513779Y125985D03*
X520866Y130709D03*
X527953Y125985D03*
X535039Y130709D03*
X513779Y131496D03*
X527953D03*
X506693Y136221D03*
X520866D03*
X535039D03*
X506693Y144882D03*
X513779Y140158D03*
X520866Y144882D03*
X527953Y140158D03*
X535039Y144882D03*
X506693Y150394D03*
X513779Y145670D03*
X520866Y150394D03*
X527953Y145670D03*
X535039Y150394D03*
X506693Y159055D03*
X513779Y154331D03*
X520866Y159055D03*
X527953Y154331D03*
X535039Y159055D03*
X506693Y164567D03*
X513779Y159843D03*
X520866Y164567D03*
X527953Y159843D03*
X535039Y164567D03*
X506693Y173229D03*
X513779Y168504D03*
X520866Y173229D03*
X527953Y168504D03*
X535039Y173229D03*
X506693Y178740D03*
X513779Y174016D03*
X520866Y178740D03*
X527953Y174016D03*
X535039Y178740D03*
X542126Y125985D03*
X549212Y130709D03*
X556299Y125985D03*
X542126Y131496D03*
X556299D03*
X549212Y136221D03*
X542126Y140158D03*
X549212Y144882D03*
X556299Y140158D03*
X542126Y145670D03*
X549212Y150394D03*
X556299Y145670D03*
X542126Y154331D03*
X549212Y159055D03*
X556299Y154331D03*
X542126Y159843D03*
X549212Y164567D03*
X556299Y159843D03*
X542126Y168504D03*
X549212Y173229D03*
X556299Y168504D03*
X542126Y174016D03*
X549212Y178740D03*
X556299Y174016D03*
X638780Y69685D03*
X629921D03*
X621063D03*
X638780Y114567D03*
X635827Y120079D03*
X629921Y114567D03*
X626969Y120079D03*
X621063Y114567D03*
X618110Y120079D03*
X638780Y99606D03*
X635827Y105118D03*
X629921Y99606D03*
X621063D03*
X626969Y105118D03*
X618110D03*
X638780Y84646D03*
X635827Y90157D03*
X626969D03*
X629921Y84646D03*
X621063D03*
X618110Y90157D03*
X635827Y75197D03*
X626969D03*
X618110D03*
X717520Y69685D03*
X708661D03*
X699803D03*
X717520Y114567D03*
X714567Y120079D03*
X708661Y114567D03*
X705709Y120079D03*
X699803Y114567D03*
X696850Y120079D03*
X717520Y99606D03*
X714567Y105118D03*
X708661Y99606D03*
X699803D03*
X705709Y105118D03*
X696850D03*
X717520Y84646D03*
X714567Y90157D03*
X705709D03*
X708661Y84646D03*
X699803D03*
X696850Y90157D03*
X714567Y75197D03*
X705709D03*
X696850D03*
G54D29*
X305906Y388386D03*
G54D20*
X75534Y625175D03*
X75300Y679300D03*
Y674300D03*
X78370Y724300D03*
Y719500D03*
X80334Y625175D03*
X81300Y675100D03*
Y680100D03*
X134223Y691027D03*
X83170Y724300D03*
Y719500D03*
X122435Y666782D03*
Y661982D03*
X155400Y717700D03*
X249500Y719500D03*
Y724300D03*
Y729100D03*
Y733900D03*
Y738700D03*
X321382Y197574D03*
X296282Y189224D03*
Y184424D03*
X301082D03*
Y189224D03*
X335132Y195874D03*
X305862Y210014D03*
X334882Y215874D03*
Y220874D03*
X321382Y202374D03*
X335132Y205974D03*
X322586Y653754D03*
X317786D03*
X312986D03*
X308186D03*
X305500Y721000D03*
X310500D03*
X304150Y674700D03*
X299350D03*
X305500Y726000D03*
X310500D03*
X521634Y38901D03*
Y34101D03*
X516834Y38901D03*
Y34101D03*
X526434Y43701D03*
X521634D03*
X516834D03*
X520000Y63400D03*
X515200Y66440D03*
X520585Y68348D03*
X508668Y79607D03*
X503550Y79500D03*
X511100Y75060D03*
X506100D03*
X511100Y70060D03*
X525200Y71440D03*
X516628Y71806D03*
X600700Y35700D03*
X595500Y35600D03*
X595700Y29800D03*
X600900Y29700D03*
X576512Y369625D03*
Y364825D03*
X581312Y369625D03*
Y364825D03*
X609200Y330400D03*
X642700Y454400D03*
X642500Y449100D03*
X642600Y459500D03*
X621600Y486619D03*
X626958Y486419D03*
X642500Y464700D03*
X629500Y482500D03*
Y477000D03*
Y471500D03*
X635000Y482500D03*
Y476500D03*
Y471000D03*
X657000Y555000D03*
X662000D03*
X661887Y560010D03*
X656887D03*
X708483Y311988D03*
X713283D03*
X723900Y326350D03*
X718940Y326270D03*
X714900Y453600D03*
X715200Y459600D03*
X706700Y413900D03*
X710200Y417400D03*
Y422900D03*
Y427900D03*
X698700Y417600D03*
Y423100D03*
Y428100D03*
X676000Y431000D03*
X671000D03*
Y421000D03*
X676000D03*
X671000Y426000D03*
X676000D03*
X715200Y465000D03*
X689500Y518500D03*
Y524000D03*
X694738Y523940D03*
X694690Y519034D03*
X687015Y658100D03*
Y653300D03*
Y648500D03*
Y643700D03*
Y682100D03*
X673950Y686104D03*
Y691104D03*
Y696104D03*
Y701104D03*
Y706104D03*
X687015Y677300D03*
Y672500D03*
Y667700D03*
Y662900D03*
X754000Y172700D03*
Y177500D03*
X798359Y351659D03*
X795193Y355540D03*
X791786Y359001D03*
X750000Y427100D03*
X754800D03*
X783800Y436000D03*
X779000D03*
X793400D03*
X788600D03*
X788400Y427100D03*
X783600D03*
X778800D03*
X774200Y436000D03*
X774000Y427100D03*
X769200D03*
X764400D03*
X759600D03*
X826993Y358840D03*
X821502Y358356D03*
X827145Y363638D03*
X821653Y363488D03*
X826900Y332500D03*
X825300Y339900D03*
X825100Y347300D03*
X828100Y352900D03*
X809792Y379122D03*
X814592D03*
X809792Y374322D03*
X814592D03*
X842900Y347200D03*
X840800Y352800D03*
X804300Y436500D03*
X813900D03*
X809100D03*
X818700D03*
X823500D03*
X827000Y516000D03*
X832000D03*
Y521000D03*
X827000D03*
X843900Y464000D03*
X848700Y465200D03*
Y470600D03*
X881147Y394517D03*
X880887Y399474D03*
G54D36*
X564803Y24409D03*
X584803D03*
X753780D03*
X773780D03*
X801024D03*
X821024D03*
G54D23*
X197243Y589764D03*
X203542Y592913D03*
X168898Y548819D03*
X172000Y577150D03*
X209841Y574016D03*
X206692D03*
X165745Y564567D03*
X168895D03*
X159449Y561417D03*
X165748D03*
X172047D03*
X162598Y558268D03*
X168898D03*
X165748Y555118D03*
X159449D03*
X168898Y567717D03*
X159449Y570866D03*
X168898Y583464D03*
Y577165D03*
X159449Y586614D03*
X162598Y580315D03*
Y586614D03*
X165748D03*
X168898D03*
X159449Y577165D03*
X156299D03*
X168898Y580315D03*
X159449D03*
X162598Y577165D03*
X165748Y580315D03*
X162598Y583464D03*
X165748Y570866D03*
Y567717D03*
X162598D03*
X172047Y570866D03*
X162597Y555118D03*
X197243Y551970D03*
X194093D03*
X200395Y555120D03*
X181497Y551970D03*
Y589764D03*
X187795Y555120D03*
X206692Y564569D03*
Y561419D03*
Y558269D03*
Y567718D03*
X203543Y574017D03*
X206692Y583465D03*
X194093Y586614D03*
X178347Y551970D03*
X175197D03*
Y558268D03*
X178347Y589764D03*
X190945Y542519D03*
X172047Y545669D03*
Y551970D03*
X159449Y545671D03*
X162599Y545669D03*
X165749D03*
X184646Y548821D03*
Y545671D03*
X209842Y567717D03*
X184645Y542519D03*
X206692Y542521D03*
X209841Y577165D03*
X159449Y542521D03*
X156299Y545671D03*
X168898Y592913D03*
X181497Y545671D03*
X209842Y545669D03*
X165749Y548819D03*
X175197Y545671D03*
X162599Y542519D03*
X168898D03*
X156299Y542521D03*
X181496Y542520D03*
X159449Y548821D03*
X206692Y589763D03*
X172047Y548819D03*
X168898Y551969D03*
X162599Y548821D03*
X194093Y589764D03*
Y592913D03*
X162598Y561417D03*
X168898Y555119D03*
X181497Y548821D03*
X178346Y545670D03*
X206692Y586614D03*
X209842Y586613D03*
X209841Y592913D03*
X162595Y564567D03*
X162598Y570866D03*
X203542Y548821D03*
Y586614D03*
Y580315D03*
X178344Y577166D03*
X178346Y586615D03*
X181497Y586614D03*
X178347Y574018D03*
Y570868D03*
X190944Y586614D03*
X200394Y570866D03*
Y574016D03*
X203543Y561418D03*
Y564568D03*
X165748Y551968D03*
X159448D03*
X178346Y555119D03*
X178347Y564569D03*
X197245Y555118D03*
X190944D03*
X181497Y555120D03*
X172048Y564569D03*
X172047Y567717D03*
X175298Y577266D03*
X209842Y558268D03*
X190944Y589764D03*
Y592913D03*
X197244Y586615D03*
X200393Y586614D03*
X194094Y542519D03*
X209842Y564567D03*
X200393Y548819D03*
X209842Y561417D03*
Y589763D03*
X206692Y580315D03*
X209841D03*
X200393Y545669D03*
X206692Y545671D03*
X200393Y592913D03*
X159448Y589764D03*
Y592913D03*
X162598Y589764D03*
X165748D03*
Y592913D03*
X165749Y542519D03*
X175197Y592913D03*
X172048D03*
X209842Y555119D03*
Y551969D03*
X181497Y592913D03*
X197244Y545669D03*
X194094Y548820D03*
X209842Y548819D03*
X175197Y548821D03*
X168898Y545669D03*
X156300Y539371D03*
X194094Y545669D03*
X197244Y542520D03*
X194094Y602362D03*
X206692Y596063D03*
X194093D03*
X209841D03*
X190945Y599213D03*
X190944Y596063D03*
X187796Y599212D03*
X184645Y599213D03*
X159448Y596063D03*
X168898D03*
X203542Y602362D03*
Y599213D03*
X206692Y602362D03*
X203542Y596063D03*
X194094Y599213D03*
X162598Y596063D03*
X165748Y599213D03*
X168898D03*
X162598D03*
X159448D03*
X172048Y596063D03*
X178346Y596064D03*
X178347Y599213D03*
X181496Y596062D03*
X209841Y599212D03*
X206692Y599213D03*
X165748Y596063D03*
X175197D03*
Y599213D03*
X172048D03*
X219800Y445700D03*
X213874Y445226D03*
X216141Y580315D03*
Y577165D03*
X212991Y567718D03*
X216141Y583465D03*
Y586614D03*
Y564569D03*
X212992Y561417D03*
X216141Y567718D03*
X219293Y567717D03*
X212992Y580315D03*
X212991Y577165D03*
Y574016D03*
X216141D03*
Y561419D03*
X212991Y583465D03*
Y542519D03*
X212992Y589764D03*
Y555119D03*
Y558268D03*
X216142Y548820D03*
X216141Y555120D03*
Y558269D03*
X222441Y548820D03*
X219291D03*
X212992Y551969D03*
X216141Y551970D03*
X212992Y548819D03*
X216141Y589762D03*
X212993Y592912D03*
X212992Y564567D03*
Y545669D03*
X216142D03*
X212992Y602363D03*
X212991Y599212D03*
X216141D03*
X781088Y294094D03*
X771653Y294093D03*
X777952Y290944D03*
X777989Y294093D03*
X774802Y290944D03*
X774835Y294088D03*
X768503Y290944D03*
X768498Y294124D03*
X765353Y290944D03*
X765325Y294102D03*
X759054Y290944D03*
X759055Y294094D03*
X755905Y290944D03*
Y294093D03*
X787401Y290944D03*
X787408Y294074D03*
X784251Y290944D03*
X784258Y294064D03*
G54D30*
X346457Y66850D03*
X353543Y70787D03*
Y62913D03*
Y55039D03*
X346457Y74724D03*
Y84567D03*
X353543Y86535D03*
Y78661D03*
G54D28*
X305906Y182874D03*
G54D11*
X80708Y44292D03*
X61024Y34449D03*
X33464D03*
X38386Y24606D03*
X108268Y44292D03*
X85630Y34449D03*
X600300Y574400D03*
X610300D03*
G54D19*
X67853Y573865D03*
X96800Y662000D03*
X90200Y667100D03*
X85400D03*
X91700Y744800D03*
X96500D03*
X101300D03*
X106100D03*
X110900D03*
X115700D03*
X120500D03*
X125300D03*
X187795Y570866D03*
X190944Y574016D03*
X304231Y261048D03*
X334582Y291284D03*
Y279784D03*
X307567Y324092D03*
X304267Y322892D03*
Y311392D03*
X307567Y310292D03*
Y298792D03*
X304267Y297692D03*
Y286192D03*
X334582Y330271D03*
X328182Y329174D03*
Y317674D03*
X334582Y316574D03*
Y305074D03*
X328182Y303977D03*
Y292477D03*
X307567Y285092D03*
Y273592D03*
X304231Y272548D03*
X304267Y373292D03*
Y361792D03*
X307567Y360692D03*
Y349192D03*
X304267Y348092D03*
Y336592D03*
X307567Y335592D03*
X328182Y379518D03*
Y368018D03*
X334582Y366974D03*
Y355474D03*
Y341771D03*
X328182Y354371D03*
Y342871D03*
X335200Y640100D03*
X330400D03*
X335000Y615400D03*
X335300Y609800D03*
X335000Y621200D03*
X325600Y640100D03*
X315520Y711720D03*
X325700Y711600D03*
X320320Y711720D03*
X628160Y569095D03*
X619400Y570451D03*
X721260Y272047D03*
X700546Y577599D03*
X691796D03*
X691296Y572599D03*
X705696D03*
X696296Y577599D03*
X709296Y572599D03*
Y577599D03*
X702096Y572599D03*
X694896D03*
X698496D03*
X704796Y577599D03*
X709569Y582496D03*
X698769D03*
X695169D03*
X691569D03*
X702369D03*
X705969D03*
X777550Y62350D03*
X737009Y237400D03*
X759073Y287810D03*
X740159Y278345D03*
X798000Y459300D03*
X751100Y405400D03*
X755900D03*
X760700D03*
X765500D03*
X770300D03*
X775100D03*
X790600Y458000D03*
X781000D03*
X785800D03*
X776200D03*
X789500Y405400D03*
X784700D03*
X779900D03*
X828000Y459300D03*
X823200D03*
X832800D03*
X818400D03*
X807600D03*
X802800D03*
X812400D03*
X830100Y501500D03*
X839700D03*
X834900D03*
G54D10*
X8500Y18279D03*
Y28279D03*
Y38279D03*
Y48279D03*
Y58279D03*
Y68279D03*
X13721Y8500D03*
X8500Y13279D03*
Y23279D03*
Y33279D03*
Y43279D03*
Y53279D03*
Y63279D03*
Y78279D03*
Y88279D03*
Y98279D03*
Y108279D03*
Y118279D03*
Y128279D03*
Y73279D03*
Y83279D03*
Y93279D03*
Y103279D03*
Y113279D03*
Y123279D03*
Y133279D03*
Y138279D03*
Y148279D03*
Y158279D03*
Y168279D03*
Y178279D03*
Y188279D03*
Y198279D03*
Y143279D03*
Y153279D03*
Y163279D03*
Y173279D03*
Y183279D03*
Y193279D03*
Y208279D03*
Y218279D03*
Y228279D03*
Y238279D03*
Y248279D03*
Y258279D03*
Y203279D03*
Y213279D03*
Y223279D03*
Y233279D03*
Y243279D03*
Y253279D03*
Y263279D03*
Y268279D03*
Y278279D03*
Y288279D03*
Y298279D03*
Y308279D03*
Y318279D03*
Y328279D03*
Y273279D03*
Y283279D03*
Y293279D03*
Y303279D03*
Y313279D03*
Y323279D03*
Y338279D03*
Y348279D03*
Y358279D03*
Y368279D03*
Y378279D03*
Y388279D03*
Y333279D03*
Y343279D03*
Y353279D03*
Y363279D03*
Y373279D03*
Y383279D03*
Y393279D03*
Y398279D03*
Y408279D03*
Y418279D03*
Y428279D03*
Y438279D03*
Y448279D03*
Y458279D03*
Y403279D03*
Y413279D03*
Y423279D03*
Y433279D03*
Y443279D03*
Y453279D03*
Y468279D03*
Y478279D03*
Y488279D03*
Y498279D03*
Y508279D03*
Y518279D03*
Y528279D03*
Y463279D03*
Y473279D03*
Y483279D03*
Y493279D03*
Y503279D03*
Y513279D03*
Y523279D03*
Y538279D03*
Y548279D03*
Y558279D03*
Y568279D03*
Y578279D03*
Y588279D03*
Y533279D03*
Y543279D03*
Y553279D03*
Y563279D03*
Y573279D03*
Y583279D03*
Y593279D03*
Y598279D03*
Y608279D03*
Y618279D03*
Y628279D03*
Y638279D03*
Y648279D03*
Y658279D03*
Y603279D03*
Y613279D03*
Y623279D03*
Y633279D03*
Y643279D03*
Y653279D03*
Y668279D03*
Y678279D03*
Y688279D03*
Y698279D03*
Y708279D03*
Y718279D03*
Y663279D03*
Y673279D03*
Y683279D03*
Y693279D03*
Y703279D03*
Y713279D03*
X8892Y723187D03*
X11090Y727806D03*
X13500Y732400D03*
X78721Y8500D03*
X68721D03*
X58721D03*
X48721D03*
X38721D03*
X28721D03*
X18721D03*
X73721D03*
X53721D03*
X43721D03*
X33721D03*
X23721D03*
X77780Y61790D03*
X73760Y67930D03*
X56960Y58900D03*
X54050Y63260D03*
X43510Y57810D03*
X29890Y54070D03*
X49460Y63690D03*
X68730Y67930D03*
X63721Y8500D03*
X37660Y566400D03*
X42597Y571789D03*
X64701Y570716D03*
Y564416D03*
X61100Y546700D03*
X64400Y539000D03*
X64884Y650984D03*
X50700Y664000D03*
X50800Y667900D03*
X65900Y671000D03*
X65700Y660900D03*
X70600Y665800D03*
X60700Y665900D03*
X70800Y660700D03*
X60800Y660900D03*
X70700Y671000D03*
X60600Y670900D03*
X65714Y665850D03*
X40309Y660700D03*
X71850Y698900D03*
X28100Y755600D03*
X33100D03*
X69057Y755280D03*
X74057D03*
X20300Y746200D03*
X15800Y736900D03*
X18100Y741500D03*
X22600Y750800D03*
X79057Y755280D03*
X108721Y8500D03*
X98721D03*
X88721D03*
X112197Y65406D03*
Y60406D03*
Y55406D03*
X103721Y8500D03*
X93721D03*
X83721D03*
X84610Y64470D03*
X98770Y60860D03*
X112197Y75406D03*
Y85406D03*
Y95406D03*
Y105406D03*
Y115406D03*
Y120406D03*
Y110406D03*
Y100406D03*
Y90406D03*
Y80406D03*
Y70406D03*
Y145406D03*
Y195406D03*
Y185406D03*
Y175406D03*
Y165406D03*
Y155406D03*
Y200406D03*
Y190406D03*
Y180406D03*
Y170406D03*
Y160406D03*
Y150406D03*
Y265406D03*
Y255406D03*
Y245406D03*
Y235406D03*
Y225406D03*
Y215406D03*
Y205406D03*
Y260406D03*
Y250406D03*
Y240406D03*
Y230406D03*
Y220406D03*
Y210406D03*
Y325406D03*
Y315406D03*
Y305406D03*
Y295406D03*
Y285406D03*
Y275406D03*
Y330406D03*
Y320406D03*
Y310406D03*
Y300406D03*
Y290406D03*
Y280406D03*
Y270406D03*
Y390406D03*
Y380406D03*
Y370406D03*
Y360406D03*
Y350406D03*
Y395406D03*
Y385406D03*
Y375406D03*
Y365406D03*
Y355406D03*
Y345406D03*
Y335406D03*
Y340406D03*
Y420406D03*
Y410406D03*
Y400406D03*
Y425406D03*
Y415406D03*
Y405406D03*
X107100Y497300D03*
X138900Y525999D03*
X135012Y510200D03*
X119400Y511500D03*
X133152Y484074D03*
X105350Y511850D03*
X94473Y547093D03*
X89901Y587466D03*
X136990Y535235D03*
X103600Y637800D03*
X103500Y645500D03*
Y650535D03*
X101400Y606300D03*
X97800D03*
X137210Y622030D03*
X134030Y620760D03*
X130630Y620900D03*
X101500Y597000D03*
X85500Y628500D03*
X122750Y616950D03*
X122000Y628700D03*
X144800Y657900D03*
X136100Y656300D03*
X125100Y656700D03*
X86500Y703100D03*
X86600Y708300D03*
X111300Y705500D03*
X135019Y706095D03*
X130019D03*
X139916Y705822D03*
X130019Y724095D03*
X135019Y714845D03*
Y719095D03*
Y723595D03*
Y710595D03*
X130019Y720495D03*
Y716895D03*
Y713295D03*
Y709695D03*
X139916Y723822D03*
Y720222D03*
Y716622D03*
Y713022D03*
Y709422D03*
X144057Y755280D03*
X134057D03*
X124057D03*
X114057D03*
X104057D03*
X94057D03*
X84057D03*
X89057D03*
X99057D03*
X109057D03*
X119057D03*
X129057D03*
X139057D03*
X146301Y460200D03*
X146263Y468562D03*
X203307Y506400D03*
X203500Y513500D03*
X207500Y503000D03*
X191418Y509981D03*
X170870Y492270D03*
X158000Y480700D03*
X146143Y481057D03*
X184646Y577165D03*
X187795D03*
X190945D03*
X187795Y574016D03*
X184646D03*
Y570866D03*
X187795Y564567D03*
X194094Y567716D03*
X190945D03*
X187795D03*
X184646D03*
X195300Y529400D03*
X156297Y558267D03*
X171020Y611020D03*
X200610Y639611D03*
X207900Y645600D03*
X169000Y640300D03*
X184967Y643983D03*
X200560Y635100D03*
X170940Y614400D03*
X191110Y611050D03*
X196855Y698355D03*
X208300Y704985D03*
X203500D03*
X198700D03*
X151130Y703440D03*
X193900Y704985D03*
X191766Y679920D03*
X202800Y660900D03*
X189000Y659900D03*
X204057Y755280D03*
X194057D03*
X184057D03*
X174057D03*
X164057D03*
X154057D03*
X149057D03*
X159057D03*
X169057D03*
X179057D03*
X189057D03*
X199057D03*
X209057D03*
X275500Y466200D03*
X211700Y513500D03*
X220100Y513400D03*
X211196Y487762D03*
X222600Y503500D03*
X246000Y516670D03*
X222500Y536161D03*
X211500Y529400D03*
X230900Y581600D03*
X229800Y593200D03*
X247400Y589600D03*
X252593Y547650D03*
X261900Y591300D03*
X247100Y582400D03*
X246611Y551511D03*
X246484Y537139D03*
X269900Y567619D03*
X255228Y631071D03*
X255648Y626127D03*
X245300Y635700D03*
X254199Y603443D03*
X254600Y597100D03*
X229137Y634881D03*
X266857Y634343D03*
X256001Y612347D03*
X258869Y603050D03*
X266571Y608619D03*
X275470Y608480D03*
X270400Y622870D03*
X264040Y648370D03*
X219200Y647200D03*
X221900Y630800D03*
X218800Y635600D03*
X230900Y649100D03*
X211706Y645349D03*
X247725Y656375D03*
X246500Y601500D03*
X234000Y629576D03*
X218200Y651400D03*
X248450Y609900D03*
X266847Y626253D03*
X229063Y638560D03*
X216600Y658400D03*
X274800Y635000D03*
X222700Y704985D03*
X217900D03*
X213100D03*
X261248Y700086D03*
X272050Y711810D03*
X267880Y704920D03*
X262634Y711233D03*
X266400Y675349D03*
X265000Y662574D03*
X247825Y670375D03*
X235100Y679921D03*
X221575Y695400D03*
X242000Y693400D03*
X274057Y755280D03*
X264057D03*
X254057D03*
X244057D03*
X234057D03*
X224057D03*
X214057D03*
X219057D03*
X229057D03*
X239057D03*
X249057D03*
X259057D03*
X269057D03*
X315120Y8500D03*
X310120D03*
X305120D03*
X300120D03*
X296020Y9420D03*
Y14420D03*
Y19420D03*
Y24420D03*
Y29420D03*
X340297Y117548D03*
X341484Y110328D03*
X322426Y223731D03*
Y227531D03*
X321197Y254433D03*
X322426Y231331D03*
X321782Y215974D03*
X306446Y247874D03*
X305382Y227474D03*
X305498Y213824D03*
X305703Y202165D03*
X306407Y206057D03*
X321281Y266486D03*
X321432Y279090D03*
X321882Y291874D03*
Y304374D03*
X321432Y316885D03*
Y329484D03*
Y342082D03*
Y354681D03*
X321202Y376887D03*
X321432Y367279D03*
X335982Y390874D03*
X307364Y505750D03*
X321976D03*
X329035Y519325D03*
X293793Y521556D03*
X321208Y519411D03*
X285800Y549394D03*
X303100Y587000D03*
X292850Y586100D03*
X293271Y557248D03*
X327110Y583660D03*
X316680Y583527D03*
X337899Y587874D03*
X285982Y542502D03*
X310350Y538293D03*
X330860Y551744D03*
X325447Y536109D03*
X339081Y628173D03*
X290300Y636900D03*
X290500Y640600D03*
X331655Y603405D03*
X339822Y609785D03*
X339847Y620281D03*
X305470Y623734D03*
X278546Y633450D03*
X281900Y640900D03*
X306486Y643750D03*
X306286Y633650D03*
X311186Y638550D03*
X301286Y638650D03*
X311386Y633450D03*
X301386Y633650D03*
X311286Y643750D03*
X301186Y643650D03*
X306300Y638600D03*
X317600Y603300D03*
X339266Y658409D03*
X318400Y678400D03*
X325900Y678500D03*
X330200Y709300D03*
X334650Y689700D03*
X335350Y684650D03*
X281400Y708200D03*
X281500Y712200D03*
X279400Y686400D03*
X294804Y695204D03*
X295634Y710070D03*
X290520Y715120D03*
X300620Y715220D03*
X290720Y705120D03*
X300720Y704920D03*
X290620Y710120D03*
X300520Y710020D03*
X295620Y705120D03*
X295820Y715220D03*
X296800Y665081D03*
X311600Y670354D03*
X319600Y670450D03*
X293300Y679700D03*
X334057Y755280D03*
X324057D03*
X314057D03*
X304057D03*
X294057D03*
X284057D03*
X279057D03*
X289057D03*
X299057D03*
X309057D03*
X319057D03*
X329057D03*
X339057D03*
X298570Y743670D03*
X306470Y743570D03*
X278553Y740020D03*
X380500Y33500D03*
Y30000D03*
X384000D03*
X381173Y49058D03*
X381156Y54116D03*
X375200Y63400D03*
X375300Y72150D03*
X374844Y87900D03*
X375000Y107300D03*
X393206Y77614D03*
X374844Y76700D03*
X362000Y124000D03*
X349072Y193574D03*
X400212Y154732D03*
X400351Y165605D03*
X349072Y189774D03*
X371775Y200577D03*
X348082Y186224D03*
X362197Y222068D03*
X362722Y237674D03*
X369000Y512700D03*
X345497Y527644D03*
X355300Y510100D03*
X353300Y521400D03*
X344700Y509000D03*
X368721Y525271D03*
X371900Y481548D03*
X365800Y498300D03*
X373500Y540305D03*
X393912Y568499D03*
X351600Y540600D03*
X348314Y585614D03*
X385600Y529107D03*
X372600Y576207D03*
X374292Y580300D03*
X355012Y582324D03*
X363008Y547309D03*
X371227Y566830D03*
X348600Y643500D03*
X344564Y628104D03*
X379400Y641800D03*
X385163Y641354D03*
X342133Y603008D03*
X391150Y613429D03*
X350500Y647600D03*
X355000Y652160D03*
X374200Y645871D03*
X370200Y636400D03*
X359036Y635900D03*
X359258Y596820D03*
X371400Y606400D03*
X358900Y612800D03*
X358800Y606300D03*
X365300Y606500D03*
X371400Y612700D03*
X371300Y618800D03*
X365500Y619000D03*
X358900Y618800D03*
X365164Y612620D03*
X383300Y600600D03*
X384410Y633530D03*
X354102Y660666D03*
X392720Y697500D03*
X376342Y711260D03*
X358296Y672460D03*
X346465Y703185D03*
X364200Y713100D03*
X369600Y693400D03*
X351100Y712100D03*
X381638Y755280D03*
X384809Y752321D03*
X387045Y747849D03*
X389281Y743376D03*
X391517Y738904D03*
X393753Y734432D03*
X395989Y729960D03*
X398225Y725488D03*
X344057Y755280D03*
X459950Y58000D03*
X496700Y32100D03*
X482693Y42200D03*
X478500Y19775D03*
X490050Y45900D03*
X506970Y18693D03*
X502830D03*
X477400Y69300D03*
X536794Y77373D03*
X531664Y78463D03*
X515915Y80576D03*
X520310Y76700D03*
X559200Y36265D03*
X552540Y64530D03*
X577100Y78600D03*
X545300Y75600D03*
X568000Y70000D03*
X576610Y388416D03*
Y393416D03*
X601500Y363600D03*
X576610Y398416D03*
Y403416D03*
Y408416D03*
Y413416D03*
Y418416D03*
Y423416D03*
Y428416D03*
Y433416D03*
Y438416D03*
Y443416D03*
Y448416D03*
Y453416D03*
Y458416D03*
Y463416D03*
Y468416D03*
Y473416D03*
Y478416D03*
Y483416D03*
Y488416D03*
Y493416D03*
Y498416D03*
Y503416D03*
Y508416D03*
Y513416D03*
Y518416D03*
Y523416D03*
Y528416D03*
Y533416D03*
Y538416D03*
Y543416D03*
Y548416D03*
Y553416D03*
Y558416D03*
Y563416D03*
Y568416D03*
Y573416D03*
Y578416D03*
Y583416D03*
Y588416D03*
Y593416D03*
Y598416D03*
Y603416D03*
Y608416D03*
Y613416D03*
Y618416D03*
Y623416D03*
Y628416D03*
Y633416D03*
Y638416D03*
Y643416D03*
Y648416D03*
Y653416D03*
Y658416D03*
Y663416D03*
Y668416D03*
Y673416D03*
Y678416D03*
Y683416D03*
Y688416D03*
Y693416D03*
Y698416D03*
Y703416D03*
Y708416D03*
Y713416D03*
Y718416D03*
X577063Y723309D03*
X579299Y727781D03*
X581535Y732253D03*
X583771Y736725D03*
X586007Y741198D03*
X588243Y745670D03*
X590479Y750142D03*
X592715Y754614D03*
X641732Y117323D03*
X632873D03*
X624015D03*
X641732Y102362D03*
X632873D03*
X624015D03*
X641732Y87402D03*
X632873D03*
X624015D03*
X641732Y72441D03*
X632873D03*
X624015D03*
X638470Y164470D03*
X634910Y169360D03*
X644100Y199850D03*
X630000Y169600D03*
X629500Y187500D03*
X666700Y205600D03*
X629400Y217300D03*
X648700Y292900D03*
X654670Y391494D03*
X616428Y379533D03*
X626772Y371336D03*
X612300Y344300D03*
X613480Y333710D03*
X629900Y339300D03*
X610300Y354800D03*
X658000Y431500D03*
Y409000D03*
Y414000D03*
Y426000D03*
Y420500D03*
X657900Y443200D03*
X655100Y436900D03*
X610000Y467500D03*
X609000Y473500D03*
Y478500D03*
Y483500D03*
X645200Y521900D03*
X650400Y517600D03*
X656400Y517500D03*
X661500Y517600D03*
X629200Y536040D03*
X629080Y539920D03*
X625500Y536100D03*
X615500Y529800D03*
X616710Y534500D03*
X610200Y555400D03*
X625300Y539900D03*
X653600Y540300D03*
X645300Y655200D03*
Y650400D03*
Y645600D03*
Y640800D03*
X655000Y705000D03*
Y700200D03*
Y695400D03*
Y690600D03*
X645300Y684000D03*
Y679200D03*
Y674400D03*
Y669600D03*
Y664800D03*
Y660000D03*
X655000Y685800D03*
X659722Y755280D03*
X649722D03*
X639722D03*
X634722D03*
X644722D03*
X654722D03*
X664722D03*
X720472Y117323D03*
X711613D03*
X702755D03*
X720472Y102362D03*
X711613D03*
X702755D03*
X720472Y87402D03*
X711613D03*
X702755D03*
X720472Y72441D03*
X711613D03*
X702755D03*
X722150Y174300D03*
X727150Y184550D03*
X722150D03*
X711150Y174300D03*
X716650Y184550D03*
X711150D03*
X705650D03*
X721261Y240551D03*
X721260Y234252D03*
X691600Y207600D03*
X721820Y315750D03*
X677300Y314900D03*
X681200D03*
X684400Y313400D03*
X688000Y313200D03*
X694675Y323900D03*
X708100Y331410D03*
X718340Y315800D03*
X731400Y362700D03*
X727000Y353000D03*
X712417Y352800D03*
X708300Y445800D03*
X728874Y470860D03*
X725366Y470722D03*
X677275Y485625D03*
X683583Y485841D03*
X702824Y476476D03*
X682400Y463400D03*
X670400Y565500D03*
Y560700D03*
Y555900D03*
Y551100D03*
Y546300D03*
Y541500D03*
Y536700D03*
X703440Y548820D03*
X710459Y554134D03*
X719626Y590829D03*
X722300Y608200D03*
X708600Y608500D03*
X729722Y755280D03*
X719722D03*
X709722D03*
X699722D03*
X689722D03*
X679722D03*
X669722D03*
X674722D03*
X684722D03*
X694722D03*
X704722D03*
X714722D03*
X724722D03*
X734722D03*
X780100Y8500D03*
X775100D03*
X770100D03*
X765100D03*
X760100D03*
X755100D03*
X750100D03*
X745100D03*
X787895D03*
X797895D03*
X792895D03*
X795832Y66750D03*
X787360Y35650D03*
X776300Y47600D03*
X761900Y81700D03*
X772700Y113000D03*
X794650Y86050D03*
X769710Y125150D03*
X766110Y125270D03*
X793957Y113436D03*
X761950Y126450D03*
X773200Y97600D03*
X749600Y199300D03*
X749400Y195600D03*
X753800Y181500D03*
X753400Y185400D03*
X741300Y185700D03*
X749455Y202200D03*
X790551Y284646D03*
X781100Y287800D03*
X780300Y309300D03*
X795026Y374556D03*
X799426Y374456D03*
X738465Y352935D03*
X735484Y429378D03*
Y434178D03*
Y462978D03*
Y458178D03*
Y453378D03*
Y448578D03*
Y443778D03*
Y438978D03*
X740300Y427100D03*
Y431900D03*
Y446300D03*
Y441500D03*
Y436700D03*
X794700Y505200D03*
X747125Y483924D03*
X743726Y483813D03*
X735484Y467778D03*
X755500Y492600D03*
X768500Y480000D03*
X740253Y483893D03*
X797323Y512162D03*
X757099Y530082D03*
X763809Y537191D03*
X782709Y537691D03*
X799722Y755280D03*
X789722D03*
X779722D03*
X769722D03*
X759722D03*
X749722D03*
X739722D03*
X744722D03*
X754722D03*
X764722D03*
X774722D03*
X784722D03*
X794722D03*
X807895Y8500D03*
X817895D03*
X827895D03*
X837895D03*
X847895D03*
X857895D03*
X862895D03*
X852895D03*
X842895D03*
X832895D03*
X822895D03*
X812895D03*
X802895D03*
X826925Y57425D03*
X802227Y208424D03*
X802246Y205826D03*
X804600Y210800D03*
X808400D03*
X810300Y326450D03*
X823250Y319350D03*
X814450Y306950D03*
X842600Y339400D03*
X841100Y332300D03*
X810946Y389734D03*
X811112Y393735D03*
X857581Y391433D03*
X851100Y407500D03*
X864727Y398458D03*
X861000Y410500D03*
X846000Y476100D03*
X810200Y494900D03*
X815100Y499800D03*
X805200Y499900D03*
X815300Y494700D03*
X805300Y494900D03*
X815200Y505000D03*
X805100Y504900D03*
X810214Y499850D03*
X810400Y505000D03*
X849050Y481050D03*
X809384Y484984D03*
X800800Y526900D03*
X821050Y533350D03*
X813150Y533450D03*
X849722Y755280D03*
X839722D03*
X829722D03*
X819722D03*
X809722D03*
X804722D03*
X814722D03*
X824722D03*
X834722D03*
X844722D03*
X854722D03*
X867895Y8500D03*
X877895D03*
X887895D03*
X897895D03*
X907895D03*
X916697Y19698D03*
Y29698D03*
Y39698D03*
Y49698D03*
Y59698D03*
Y69698D03*
Y64698D03*
Y54698D03*
Y44698D03*
Y34698D03*
Y24698D03*
Y14698D03*
X912895Y8500D03*
X902895D03*
X892895D03*
X882895D03*
X872895D03*
X916697Y79698D03*
Y89698D03*
Y99698D03*
Y109698D03*
Y119698D03*
Y129698D03*
Y134698D03*
Y124698D03*
Y114698D03*
Y104698D03*
Y94698D03*
Y84698D03*
Y74698D03*
Y139698D03*
Y149698D03*
Y159698D03*
Y169698D03*
Y179698D03*
Y189698D03*
Y199698D03*
Y194698D03*
Y184698D03*
Y174698D03*
Y164698D03*
Y154698D03*
Y144698D03*
Y209698D03*
Y219698D03*
Y229698D03*
Y239698D03*
Y249698D03*
Y259698D03*
Y264698D03*
Y254698D03*
Y244698D03*
Y234698D03*
Y224698D03*
Y214698D03*
Y204698D03*
X888551Y226649D03*
X882871Y243771D03*
X892449Y241249D03*
X886300Y221150D03*
X916697Y269698D03*
Y279698D03*
Y289698D03*
Y299698D03*
Y309698D03*
Y319698D03*
Y329698D03*
Y324698D03*
Y314698D03*
Y304698D03*
Y294698D03*
Y284698D03*
Y274698D03*
X896969Y301500D03*
X916697Y339698D03*
Y349698D03*
Y359698D03*
Y369698D03*
Y379698D03*
Y389698D03*
Y394698D03*
Y384698D03*
Y374698D03*
Y364698D03*
Y354698D03*
Y344698D03*
Y334698D03*
Y399698D03*
Y409698D03*
Y419698D03*
Y429698D03*
Y439698D03*
Y449698D03*
Y459698D03*
Y454698D03*
Y444698D03*
Y434698D03*
Y424698D03*
Y414698D03*
Y404698D03*
X874727Y398458D03*
X869727D03*
X872750Y403400D03*
X916697Y469698D03*
Y479698D03*
Y489698D03*
Y499698D03*
Y509698D03*
Y519698D03*
Y524698D03*
Y514698D03*
Y504698D03*
Y494698D03*
Y484698D03*
Y474698D03*
Y464698D03*
Y529698D03*
Y539698D03*
Y549698D03*
Y559698D03*
Y569698D03*
Y579698D03*
Y589698D03*
Y584698D03*
Y574698D03*
Y564698D03*
Y554698D03*
Y544698D03*
Y534698D03*
Y599698D03*
Y609698D03*
Y619698D03*
Y629698D03*
Y639698D03*
Y649698D03*
Y659698D03*
Y654698D03*
Y644698D03*
Y634698D03*
Y624698D03*
Y614698D03*
Y604698D03*
Y594698D03*
Y669698D03*
Y679698D03*
Y689698D03*
Y699698D03*
Y709698D03*
Y719698D03*
Y714698D03*
Y704698D03*
Y694698D03*
Y684698D03*
Y674698D03*
Y664698D03*
X914700Y726100D03*
X912436Y730603D03*
X910200Y735300D03*
X907564Y739747D03*
X905500Y744400D03*
X903192Y748791D03*
X900800Y753700D03*
X894722Y755280D03*
G54D35*
X488838Y164744D03*
G54D13*
X18700Y54650D03*
X209189Y37075D03*
Y383483D03*
X489331Y245605D03*
Y698924D03*
X901000Y21400D03*
X902500Y676000D03*
G54D34*
X488838Y137225D03*
G54D16*
X89764Y238386D03*
X309252Y413583D03*
G54D24*
X163189Y669291D03*
G54D38*
X629921Y57874D03*
X708661D03*
G54D40*
X652756Y180000D03*
X865353Y332598D03*
G54D27*
X339331Y91929D03*
X360669Y49803D03*
G54D22*
X90157Y413583D03*
X309055Y157677D03*
G54D15*
X70865Y98425D03*
Y472440D03*
X314960D03*
X405511Y39370D03*
X364173Y740157D03*
X612204Y433070D03*
Y740157D03*
X875984Y433070D03*
Y740157D03*
G54D21*
X49213D03*
X875985Y59055D03*
G54D17*
X34132Y521245D03*
X34175Y526969D03*
X28800Y549474D03*
X29158Y543855D03*
X29058Y538228D03*
X28782Y555119D03*
X29165Y532612D03*
X33697Y560866D03*
X71002Y577013D03*
X67852Y586463D03*
Y583313D03*
X132100Y493000D03*
X114070Y481948D03*
X179000Y499800D03*
X186735Y463748D03*
X175100Y477000D03*
X184645Y589764D03*
Y539370D03*
X187795Y592914D03*
Y602363D03*
X421653Y126378D03*
X435827D03*
X450000D03*
X464173D03*
X428740Y121654D03*
X442913D03*
X457086D03*
X471260D03*
X421653Y183071D03*
X435827D03*
X450000D03*
X464173D03*
X421653Y140551D03*
X428740Y135827D03*
X435827Y140551D03*
X442913Y135827D03*
X450000Y140551D03*
X457086Y135827D03*
X464173Y140551D03*
X471260Y135827D03*
X421653Y154725D03*
X428740Y150000D03*
X435827Y154725D03*
X442913Y150000D03*
X450000Y154725D03*
X457086Y150000D03*
X464173Y154725D03*
X471260Y150000D03*
X421653Y168898D03*
X428740Y164173D03*
X435827Y168898D03*
X442913Y164173D03*
X450000Y168898D03*
X457086Y164173D03*
X464173Y168898D03*
X471260Y164173D03*
X506693Y126378D03*
X520866D03*
X535039D03*
X513779Y121654D03*
X527953D03*
X506693Y183071D03*
X520866D03*
X535039D03*
X506693Y140551D03*
X513779Y135827D03*
X520866Y140551D03*
X527953Y135827D03*
X535039Y140551D03*
X506693Y154725D03*
X513779Y150000D03*
X520866Y154725D03*
X527953Y150000D03*
X535039Y154725D03*
X506693Y168898D03*
X513779Y164173D03*
X520866Y168898D03*
X527953Y164173D03*
X535039Y168898D03*
X549212Y126378D03*
X542126Y121654D03*
X556299D03*
X549212Y183071D03*
X542126Y135827D03*
X549212Y140551D03*
X556299Y135827D03*
X542126Y150000D03*
X549212Y154725D03*
X556299Y150000D03*
X542126Y164173D03*
X549212Y168898D03*
X556299Y164173D03*
X704579Y258164D03*
X730710Y256302D03*
X733858Y256299D03*
Y253149D03*
X730710Y253152D03*
X733859Y234253D03*
Y237403D03*
X730710D03*
Y234254D03*
X733858Y243700D03*
Y246849D03*
Y249999D03*
Y265747D03*
X730710Y240553D03*
Y243702D03*
Y246852D03*
Y250002D03*
Y265750D03*
X721295Y221651D03*
X718089Y243684D03*
X721260Y253150D03*
Y259449D03*
Y265748D03*
X721261Y246851D03*
X733859Y240552D03*
X727559Y259449D03*
Y265748D03*
Y253150D03*
Y240551D03*
X727560Y246851D03*
X727559Y221654D03*
Y234252D03*
X727594Y227950D03*
X696600Y241500D03*
X701500Y250564D03*
X730710Y281496D03*
X733859D03*
Y275198D03*
X730710Y272048D03*
X733858Y268897D03*
X730710Y268899D03*
X721260Y275196D03*
X733859Y278346D03*
X730708Y290944D03*
X724409D03*
X727559Y272047D03*
Y278346D03*
X784277Y243713D03*
X784253Y227953D03*
Y231103D03*
X752756Y234253D03*
Y231103D03*
Y224804D03*
Y227954D03*
X749606Y231103D03*
Y234253D03*
Y227954D03*
Y224804D03*
X737008Y256299D03*
X740158D03*
Y253149D03*
X737008D03*
X771655Y237402D03*
X737008Y243700D03*
Y246849D03*
Y249999D03*
Y265747D03*
X740158Y246849D03*
Y265747D03*
X740122Y243700D03*
X740158Y249999D03*
X752756Y221654D03*
X737008D03*
X771654Y253150D03*
X777954Y237402D03*
Y227953D03*
Y231103D03*
X765355Y265749D03*
X771654Y259449D03*
Y265749D03*
X793701Y221654D03*
X781103Y227954D03*
X784277Y246863D03*
X784267Y259426D03*
X746457Y224804D03*
X755906D03*
X737009Y227953D03*
Y234253D03*
Y231103D03*
X774804Y221655D03*
Y224804D03*
Y227954D03*
X746457D03*
X755906D03*
X746457Y231103D03*
X755906D03*
X746457Y234253D03*
X755906D03*
X759056Y253150D03*
X765355Y234253D03*
X765354Y231102D03*
X765355Y227953D03*
X765354Y246850D03*
X784277Y253162D03*
X740132Y240562D03*
X759055Y221654D03*
X765355Y224804D03*
X771654Y215355D03*
Y209056D03*
Y212205D03*
X746457Y240552D03*
X752757D03*
X759056D03*
X746421Y253149D03*
X765354Y221654D03*
X743307D03*
X762205Y215355D03*
X781103Y237402D03*
Y231103D03*
X787402Y221654D03*
X787401Y215354D03*
X746457Y246850D03*
X752720Y253149D03*
X752757Y246851D03*
X765355Y253150D03*
X759056Y246851D03*
X746433Y265761D03*
X746457Y259449D03*
X752757D03*
Y265749D03*
X765355Y259449D03*
X759056Y265749D03*
X759031Y259461D03*
X777976Y265761D03*
X784267Y256276D03*
X793701Y231103D03*
X793672Y243709D03*
X799991Y249972D03*
X799972Y262588D03*
X796822D03*
Y256289D03*
X790551Y259486D03*
X790538Y265723D03*
X793701Y237402D03*
X777976Y259461D03*
X781102Y221654D03*
X749606D03*
X762205Y212205D03*
X762173Y294089D03*
X762229Y290933D03*
X752756Y278346D03*
X774826Y268910D03*
X737009Y281496D03*
X740159D03*
X759031Y275209D03*
X765356Y272048D03*
Y275197D03*
Y278347D03*
X740158Y272046D03*
X737008D03*
Y268897D03*
X740158D03*
X746457Y272047D03*
Y275197D03*
X752757D03*
X752731Y272060D03*
X762181D03*
X759031D03*
X762206Y275197D03*
Y278347D03*
X737009Y275196D03*
X787419Y278354D03*
X737007Y290944D03*
X749579Y297254D03*
X787402Y297243D03*
X781102Y297244D03*
X771654Y297243D03*
X759058Y300414D03*
X768503Y287794D03*
X774802D03*
X787400Y287795D03*
X749607Y275197D03*
X774789Y275174D03*
X784221Y284652D03*
X777915Y281496D03*
X762189Y281514D03*
X768489Y281474D03*
X777953Y275198D03*
Y278347D03*
X784290Y272047D03*
X743306Y290944D03*
X749606Y278346D03*
X749593Y284670D03*
X799999Y290944D03*
Y284645D03*
Y278345D03*
X799974Y272058D03*
X793701Y300393D03*
X790519Y272053D03*
X790550Y287795D03*
X749605Y290944D03*
X762204Y287794D03*
X781064Y272047D03*
X784243Y278318D03*
X816079Y250464D03*
X807468Y234464D03*
X808923Y245979D03*
X806968Y253464D03*
X803300Y303700D03*
G54D18*
X64277Y502177D03*
X75399Y502179D03*
X69904Y502077D03*
X75197Y572437D03*
X67853Y558117D03*
X97926Y502300D03*
X86699D03*
X81094Y502166D03*
X89899Y558115D03*
X86750Y573864D03*
X89899D03*
X86750Y567565D03*
X89899Y564415D03*
X106272Y547370D03*
X93048Y577014D03*
X108371Y577258D03*
X99600Y673500D03*
Y678500D03*
Y683500D03*
X175197Y589764D03*
X209842Y583464D03*
X190945Y570866D03*
X206692Y592913D03*
X194094Y539370D03*
X203542Y545671D03*
X197243Y539371D03*
X206692Y555120D03*
X194093D03*
X184646D03*
X153149Y536221D03*
X165748Y558268D03*
X172048Y555120D03*
Y589764D03*
X168898D03*
Y561417D03*
Y570866D03*
X156299Y586614D03*
Y580315D03*
X159449Y567717D03*
X156299Y570866D03*
X197243Y592913D03*
X200393Y589764D03*
X187794Y586614D03*
X203542Y589764D03*
X165748Y583464D03*
X203605Y605450D03*
X200393Y596063D03*
X153149Y605513D03*
X148249Y695765D03*
X212992Y586614D03*
X222440Y605512D03*
X582219Y386612D03*
X599998Y391270D03*
X724410Y281496D03*
X768505Y243702D03*
X765353Y237402D03*
X740158Y275197D03*
G54D41*
X769266Y326534D03*
X751566Y327434D03*
X799534Y339466D03*
X760252Y353266D03*
X768384Y345134D03*
X761134Y334666D03*
X772352Y341266D03*
X780484Y333134D03*
X777434Y353566D03*
X785566Y345434D03*
X789334Y341766D03*
X797466Y333634D03*
X743434Y335566D03*
X749534Y346566D03*
X757666Y338434D03*
X807666Y331334D03*
X825646Y328193D03*
X817514Y336325D03*
G54D42*
X843419Y261781D03*
X837619Y255281D03*
X828781Y264119D03*
X836955Y245662D03*
X828117Y254500D03*
X854419Y307581D03*
X845581Y316419D03*
X858919Y292081D03*
X850081Y300919D03*
X852919Y286081D03*
X844081Y294919D03*
X849419Y267581D03*
X840581Y276419D03*
X847419Y280581D03*
X838581Y289419D03*
X834581Y270619D03*
G54D37*
X574803Y24409D03*
X763780D03*
X811024D03*
G54D31*
X346457Y57007D03*
%LPC*%
G75*
G54D43*
G01X-13131Y-65072D02*
Y-145072D01*
G01D02*
X1244069D01*
G01X-29131Y-65072D02*
Y-33072D01*
G01X-13131Y-65072D02*
X1244069D01*
G01X-13131Y-100572D02*
X1244069D01*
G01X-17131Y-49072D02*
G02I-12000J0D01*
G01X-22281D02*
G02I-6850J0D01*
G01X-13131D02*
X-45131D01*
G01X456569Y-65072D02*
Y-145072D01*
G01X594069Y-65072D02*
Y-145072D01*
G01X709069Y-65072D02*
Y-145072D01*
G01X876569Y-65072D02*
Y-145072D01*
G01X1046569Y-65072D02*
Y-145072D01*
G01X1244069Y-65072D02*
Y-145072D01*
G01X1272069Y-49072D02*
G02I-12000J0D01*
G01X1266919D02*
G02I-6850J0D01*
G01X1276069D02*
X1244069D01*
G01X1260069Y-65072D02*
Y-33072D01*
G54D44*
G01X13215Y-125739D02*
X14089Y-124864D01*
X14744Y-123406D01*
X15181Y-121363D01*
X14744Y-119614D01*
X13871Y-118447D01*
X12342Y-117572D01*
X6447D01*
Y-135072D01*
X13652D01*
X15181Y-133906D01*
X16054Y-132155D01*
X16491Y-130114D01*
X16054Y-128072D01*
X14744Y-126322D01*
X13215Y-125739D01*
X6447D01*
G01X25912Y-135072D02*
Y-123406D01*
G01Y-125739D02*
X27004Y-124572D01*
X28096Y-123697D01*
X29624Y-123406D01*
X30715Y-123697D01*
X32026Y-124572D01*
G01X41884Y-140322D02*
X43194Y-140905D01*
X44941Y-140322D01*
X46032Y-139156D01*
X46906Y-137697D01*
X48215Y-133031D01*
X51054Y-123406D01*
G01X44067D02*
X48215Y-133031D01*
G01X67462Y-124864D02*
X65934Y-123697D01*
X64624Y-123406D01*
X62877Y-123989D01*
X61567Y-125155D01*
X60694Y-127197D01*
X60475Y-129239D01*
X60694Y-131281D01*
X61567Y-133031D01*
X62877Y-134489D01*
X64624Y-135072D01*
X66152Y-134489D01*
X67462Y-133322D01*
G01X78194Y-127197D02*
X85181D01*
X84526Y-125155D01*
X83434Y-123989D01*
X81906Y-123406D01*
X80377Y-123697D01*
X79067Y-124572D01*
X78194Y-126614D01*
X77757Y-128364D01*
Y-130114D01*
X78194Y-131864D01*
X79286Y-133614D01*
X80596Y-134780D01*
X82124Y-135072D01*
X83652Y-134489D01*
X85181Y-132739D01*
G01X121272Y-119031D02*
X119962Y-118155D01*
X118434Y-117572D01*
X116687D01*
X114722Y-118447D01*
X113194Y-119905D01*
X112102Y-121656D01*
X111229Y-124572D01*
X111010Y-127197D01*
X111447Y-129822D01*
X112102Y-131572D01*
X113412Y-133322D01*
X114941Y-134489D01*
X116469Y-135072D01*
X117997D01*
X119526Y-134489D01*
X120836Y-133614D01*
X121928Y-132448D01*
G01X137899Y-135072D02*
Y-123406D01*
G01Y-125447D02*
X137026Y-124281D01*
X135715Y-123697D01*
X134187Y-123406D01*
X132659Y-123989D01*
X131349Y-125155D01*
X130475Y-126905D01*
X130039Y-129239D01*
X130475Y-131572D01*
X131349Y-133322D01*
X132659Y-134489D01*
X134187Y-135072D01*
X135715Y-134780D01*
X137026Y-133906D01*
X137899Y-132739D01*
G01X147757Y-135072D02*
Y-123406D01*
G01Y-126322D02*
X148631Y-124864D01*
X149941Y-123697D01*
X151687Y-123406D01*
X153215Y-123697D01*
X154526Y-124864D01*
X155181Y-126905D01*
Y-135072D01*
G01X164384Y-140322D02*
X165694Y-140905D01*
X167441Y-140322D01*
X168532Y-139156D01*
X169406Y-137697D01*
X170715Y-133031D01*
X173554Y-123406D01*
G01X166567D02*
X170715Y-133031D01*
G01X186469Y-135072D02*
X185159Y-134780D01*
X183849Y-133614D01*
X182975Y-131572D01*
X182539Y-129239D01*
X182975Y-126905D01*
X183849Y-124864D01*
X185159Y-123697D01*
X186469Y-123406D01*
X187779Y-123697D01*
X189089Y-124864D01*
X189962Y-126905D01*
X190181Y-129239D01*
X189962Y-131572D01*
X189089Y-133614D01*
X187779Y-134780D01*
X186469Y-135072D01*
G01X200257D02*
Y-123406D01*
G01Y-126322D02*
X201131Y-124864D01*
X202441Y-123697D01*
X204187Y-123406D01*
X205715Y-123697D01*
X207026Y-124864D01*
X207681Y-126905D01*
Y-135072D01*
G01X236349Y-117572D02*
X241589D01*
G01X238969D02*
Y-135072D01*
G01X236349D02*
X241589D01*
G01X256469D02*
X254722Y-134780D01*
X253194Y-133614D01*
X251884Y-131864D01*
X251010Y-129822D01*
X250574Y-127489D01*
Y-125155D01*
X251010Y-122822D01*
X251884Y-120780D01*
X253194Y-119031D01*
X254722Y-117864D01*
X256469Y-117572D01*
X258215Y-117864D01*
X259744Y-119031D01*
X261054Y-120780D01*
X261928Y-122822D01*
X262364Y-125155D01*
Y-127489D01*
X261928Y-129822D01*
X261054Y-131864D01*
X259744Y-133614D01*
X258215Y-134780D01*
X256469Y-135072D01*
G01X268292D02*
Y-117572D01*
X273969Y-132155D01*
X279646Y-117572D01*
Y-135072D01*
G01X307877Y-140905D02*
X305694Y-137989D01*
X304602Y-135072D01*
Y-123406D01*
X305694Y-120489D01*
X307877Y-117572D01*
G01X321010Y-123406D02*
X323631Y-135072D01*
X326469Y-123406D01*
X329307Y-135072D01*
X331928Y-123406D01*
G01X340039Y-135655D02*
X347899Y-117572D01*
G01X376349D02*
X381589D01*
G01X378969D02*
Y-135072D01*
G01X376349D02*
X381589D01*
G01X396469D02*
X394722Y-134780D01*
X393194Y-133614D01*
X391884Y-131864D01*
X391010Y-129822D01*
X390574Y-127489D01*
Y-125155D01*
X391010Y-122822D01*
X391884Y-120780D01*
X393194Y-119031D01*
X394722Y-117864D01*
X396469Y-117572D01*
X398215Y-117864D01*
X399744Y-119031D01*
X401054Y-120780D01*
X401928Y-122822D01*
X402364Y-125155D01*
Y-127489D01*
X401928Y-129822D01*
X401054Y-131864D01*
X399744Y-133614D01*
X398215Y-134780D01*
X396469Y-135072D01*
G01X418772Y-119031D02*
X417462Y-118155D01*
X415934Y-117572D01*
X414187D01*
X412222Y-118447D01*
X410694Y-119905D01*
X409602Y-121656D01*
X408729Y-124572D01*
X408510Y-127197D01*
X408947Y-129822D01*
X409602Y-131572D01*
X410912Y-133322D01*
X412441Y-134489D01*
X413969Y-135072D01*
X415497D01*
X417026Y-134489D01*
X418336Y-133614D01*
X419428Y-132448D01*
G01X432561Y-140905D02*
X434744Y-137989D01*
X435836Y-135072D01*
Y-123406D01*
X434744Y-120489D01*
X432561Y-117572D01*
G01X180792Y-90072D02*
Y-72572D01*
X186469Y-87155D01*
X192146Y-72572D01*
Y-90072D01*
G01X203969D02*
X202659Y-89780D01*
X201349Y-88614D01*
X200475Y-86572D01*
X200039Y-84239D01*
X200475Y-81905D01*
X201349Y-79864D01*
X202659Y-78697D01*
X203969Y-78406D01*
X205279Y-78697D01*
X206589Y-79864D01*
X207462Y-81905D01*
X207681Y-84239D01*
X207462Y-86572D01*
X206589Y-88614D01*
X205279Y-89780D01*
X203969Y-90072D01*
G01X225399Y-72572D02*
Y-90072D01*
G01Y-87448D02*
X224526Y-88906D01*
X223215Y-89780D01*
X221687Y-90072D01*
X219941Y-89489D01*
X218631Y-88031D01*
X217757Y-86281D01*
X217539Y-84239D01*
X217757Y-82197D01*
X218631Y-80447D01*
X219941Y-78989D01*
X221687Y-78406D01*
X223215Y-78697D01*
X224307Y-79281D01*
X225399Y-80447D01*
G01X235694Y-82197D02*
X242681D01*
X242026Y-80155D01*
X240934Y-78989D01*
X239406Y-78406D01*
X237877Y-78697D01*
X236567Y-79572D01*
X235694Y-81614D01*
X235257Y-83364D01*
Y-85114D01*
X235694Y-86864D01*
X236786Y-88614D01*
X238096Y-89780D01*
X239624Y-90072D01*
X241152Y-89489D01*
X242681Y-87739D01*
G01X256469Y-90072D02*
Y-72572D01*
G01X490269Y-135072D02*
Y-117572D01*
X487649Y-121072D01*
G01Y-135072D02*
X492889D01*
G01X503621Y-127781D02*
X505149Y-125739D01*
X506459Y-124572D01*
X508206Y-123989D01*
X509734Y-124572D01*
X510826Y-125739D01*
X511699Y-127489D01*
X511917Y-129530D01*
X511699Y-131281D01*
X510826Y-133031D01*
X509515Y-134489D01*
X507987Y-135072D01*
X506241Y-134489D01*
X504712Y-132739D01*
X503839Y-130114D01*
X503621Y-127197D01*
X504057Y-123406D01*
X504712Y-121363D01*
X505804Y-119322D01*
X507332Y-117864D01*
X508861Y-117572D01*
X510389Y-118155D01*
X511481Y-119614D01*
G01X520466Y-131572D02*
X521775Y-133614D01*
X523522Y-134780D01*
X525487Y-135072D01*
X527234Y-134780D01*
X528981Y-133322D01*
X530072Y-131572D01*
X530291Y-129822D01*
X529854Y-127781D01*
X528326Y-126322D01*
X526797Y-125739D01*
X524832D01*
G01X526797D02*
X528107Y-124864D01*
X529199Y-123406D01*
X529636Y-121656D01*
X529199Y-119905D01*
X528107Y-118447D01*
X526142Y-117572D01*
X524177Y-117864D01*
X522212Y-119031D01*
G01X542769Y-135072D02*
Y-117572D01*
X540149Y-121072D01*
G01Y-135072D02*
X545389D01*
G01X560269D02*
X561797Y-134780D01*
X563544Y-133906D01*
X564636Y-132448D01*
X565072Y-130405D01*
X564636Y-128364D01*
X563326Y-126614D01*
X561361Y-125739D01*
X559177D01*
X557867Y-125155D01*
X556775Y-123697D01*
X556339Y-121656D01*
X556994Y-119614D01*
X558522Y-118155D01*
X560269Y-117572D01*
X562015Y-118155D01*
X563544Y-119614D01*
X564199Y-121656D01*
X563762Y-123697D01*
X562671Y-125155D01*
X561361Y-125739D01*
X559177D01*
X557212Y-126614D01*
X555902Y-128364D01*
X555466Y-130405D01*
X555902Y-132448D01*
X556994Y-133906D01*
X558741Y-134780D01*
X560269Y-135072D01*
G01X477152Y-90072D02*
Y-72572D01*
X482392D01*
X484139Y-73447D01*
X485449Y-75489D01*
X485886Y-77822D01*
X485449Y-80155D01*
X484357Y-81905D01*
X482392Y-82781D01*
X477152D01*
G01X503822Y-74031D02*
X502512Y-73155D01*
X500984Y-72572D01*
X499237D01*
X497272Y-73447D01*
X495744Y-74905D01*
X494652Y-76656D01*
X493779Y-79572D01*
X493560Y-82197D01*
X493997Y-84822D01*
X494652Y-86572D01*
X495962Y-88322D01*
X497491Y-89489D01*
X499019Y-90072D01*
X500547D01*
X502076Y-89489D01*
X503386Y-88614D01*
X504478Y-87448D01*
G01X518265Y-80739D02*
X519139Y-79864D01*
X519794Y-78406D01*
X520231Y-76363D01*
X519794Y-74614D01*
X518921Y-73447D01*
X517392Y-72572D01*
X511497D01*
Y-90072D01*
X518702D01*
X520231Y-88906D01*
X521104Y-87155D01*
X521541Y-85114D01*
X521104Y-83072D01*
X519794Y-81322D01*
X518265Y-80739D01*
X511497D01*
G01X527469Y-95905D02*
X540569D01*
G01X546497Y-90072D02*
Y-72572D01*
X556541Y-90072D01*
Y-72572D01*
G01X569019Y-90072D02*
X567272Y-89780D01*
X565744Y-88614D01*
X564434Y-86864D01*
X563560Y-84822D01*
X563124Y-82489D01*
Y-80155D01*
X563560Y-77822D01*
X564434Y-75780D01*
X565744Y-74031D01*
X567272Y-72864D01*
X569019Y-72572D01*
X570765Y-72864D01*
X572294Y-74031D01*
X573604Y-75780D01*
X574478Y-77822D01*
X574914Y-80155D01*
Y-82489D01*
X574478Y-84822D01*
X573604Y-86864D01*
X572294Y-88614D01*
X570765Y-89780D01*
X569019Y-90072D01*
G01X647421Y-120489D02*
X648731Y-118739D01*
X650259Y-117864D01*
X652006Y-117572D01*
X654189Y-118155D01*
X655717Y-119614D01*
X656154Y-121363D01*
X655936Y-123114D01*
X655062Y-124572D01*
X650696Y-127489D01*
X648731Y-129530D01*
X647421Y-132448D01*
X646984Y-135072D01*
X656154D01*
G01X619860Y-72572D02*
X625319Y-90072D01*
X630778Y-72572D01*
G01X647186Y-90072D02*
X638452D01*
Y-72572D01*
X647186D01*
G01X643692Y-81030D02*
X638452D01*
G01X655952Y-90072D02*
Y-72572D01*
X661411D01*
X663157Y-73447D01*
X664249Y-74614D01*
X664686Y-76947D01*
X664249Y-79281D01*
X662939Y-80739D01*
X661411Y-81614D01*
X655952D01*
G01X661411D02*
X664686Y-90072D01*
G01X677819Y-90655D02*
X677382Y-90364D01*
Y-89780D01*
X677819Y-89489D01*
X678256Y-89780D01*
Y-90364D01*
X677819Y-90655D01*
G01X832136Y-117572D02*
Y-135072D01*
X823402D01*
G01X810706D02*
X810269Y-131281D01*
X809614Y-128072D01*
X808741Y-125155D01*
X807649Y-121947D01*
X805902Y-117572D01*
X814636D01*
G01X791459Y-126322D02*
X787092D01*
Y-131572D01*
X788402Y-133322D01*
X789931Y-134489D01*
X792114Y-135072D01*
X794297Y-134489D01*
X795826Y-133322D01*
X797136Y-131572D01*
X798009Y-129530D01*
X798446Y-127197D01*
Y-125155D01*
X798009Y-123406D01*
X797136Y-121363D01*
X795826Y-119614D01*
X794516Y-118447D01*
X792769Y-117572D01*
X791241D01*
X789494Y-118155D01*
X788184Y-119322D01*
G01X780291Y-135072D02*
Y-117572D01*
X770247Y-135072D01*
Y-117572D01*
G01X762572Y-135072D02*
Y-117572D01*
X758206D01*
X756459Y-118447D01*
X755149Y-119614D01*
X754057Y-121363D01*
X753184Y-123406D01*
X752966Y-126322D01*
X753184Y-129239D01*
X754057Y-131281D01*
X755149Y-133031D01*
X756459Y-134197D01*
X758206Y-135072D01*
X762572D01*
G01X753402Y-72572D02*
Y-90072D01*
X762136D01*
G01X779199D02*
Y-78406D01*
G01Y-80447D02*
X778326Y-79281D01*
X777015Y-78697D01*
X775487Y-78406D01*
X773959Y-78989D01*
X772649Y-80155D01*
X771775Y-81905D01*
X771339Y-84239D01*
X771775Y-86572D01*
X772649Y-88322D01*
X773959Y-89489D01*
X775487Y-90072D01*
X777015Y-89780D01*
X778326Y-88906D01*
X779199Y-87739D01*
G01X788184Y-95322D02*
X789494Y-95905D01*
X791241Y-95322D01*
X792332Y-94156D01*
X793206Y-92697D01*
X794515Y-88031D01*
X797354Y-78406D01*
G01X790367D02*
X794515Y-88031D01*
G01X806994Y-82197D02*
X813981D01*
X813326Y-80155D01*
X812234Y-78989D01*
X810706Y-78406D01*
X809177Y-78697D01*
X807867Y-79572D01*
X806994Y-81614D01*
X806557Y-83364D01*
Y-85114D01*
X806994Y-86864D01*
X808086Y-88614D01*
X809396Y-89780D01*
X810924Y-90072D01*
X812452Y-89489D01*
X813981Y-87739D01*
G01X824712Y-90072D02*
Y-78406D01*
G01Y-80739D02*
X825804Y-79572D01*
X826896Y-78697D01*
X828424Y-78406D01*
X829515Y-78697D01*
X830826Y-79572D01*
G01X917819Y-135072D02*
X916072Y-134780D01*
X914544Y-133614D01*
X913234Y-131864D01*
X912360Y-129822D01*
X911924Y-127489D01*
Y-125155D01*
X912360Y-122822D01*
X913234Y-120780D01*
X914544Y-119031D01*
X916072Y-117864D01*
X917819Y-117572D01*
X919565Y-117864D01*
X921094Y-119031D01*
X922404Y-120780D01*
X923278Y-122822D01*
X923714Y-125155D01*
Y-127489D01*
X923278Y-129822D01*
X922404Y-131864D01*
X921094Y-133614D01*
X919565Y-134780D01*
X917819Y-135072D01*
G01X919565Y-130405D02*
X922186Y-135072D01*
G01X930516Y-117572D02*
Y-130114D01*
X931389Y-132739D01*
X933136Y-134489D01*
X935319Y-135072D01*
X937502Y-134489D01*
X939249Y-132739D01*
X940122Y-130114D01*
Y-117572D01*
G01X950199D02*
X955439D01*
G01X952819D02*
Y-135072D01*
G01X950199D02*
X955439D01*
G01X965297D02*
Y-117572D01*
X975341Y-135072D01*
Y-117572D01*
G01X992622Y-119031D02*
X991312Y-118155D01*
X989784Y-117572D01*
X988037D01*
X986072Y-118447D01*
X984544Y-119905D01*
X983452Y-121656D01*
X982579Y-124572D01*
X982360Y-127197D01*
X982797Y-129822D01*
X983452Y-131572D01*
X984762Y-133322D01*
X986291Y-134489D01*
X987819Y-135072D01*
X989347D01*
X990876Y-134489D01*
X992186Y-133614D01*
X993278Y-132448D01*
G01X1005319Y-135072D02*
Y-127197D01*
X1000952Y-117572D01*
G01X1009686D02*
X1005319Y-127197D01*
G01X895516Y-90072D02*
Y-72572D01*
X899882D01*
X901629Y-73447D01*
X902939Y-74614D01*
X904031Y-76363D01*
X904904Y-78406D01*
X905122Y-81322D01*
X904904Y-84239D01*
X904031Y-86281D01*
X902939Y-88031D01*
X901629Y-89197D01*
X899882Y-90072D01*
X895516D01*
G01X914544Y-82197D02*
X921531D01*
X920876Y-80155D01*
X919784Y-78989D01*
X918256Y-78406D01*
X916727Y-78697D01*
X915417Y-79572D01*
X914544Y-81614D01*
X914107Y-83364D01*
Y-85114D01*
X914544Y-86864D01*
X915636Y-88614D01*
X916946Y-89780D01*
X918474Y-90072D01*
X920002Y-89489D01*
X921531Y-87739D01*
G01X932044Y-88031D02*
X933136Y-89197D01*
X934664Y-90072D01*
X935974D01*
X937284Y-89489D01*
X938157Y-88614D01*
X938594Y-87448D01*
X938376Y-85697D01*
X937502Y-84822D01*
X933572Y-83072D01*
X932699Y-81030D01*
X933136Y-79572D01*
X934009Y-78697D01*
X935319Y-78406D01*
X936629Y-78697D01*
X937939Y-79572D01*
G01X952819Y-78406D02*
Y-90072D01*
G01Y-73739D02*
X952382Y-73447D01*
Y-72864D01*
X952819Y-72572D01*
X953256Y-72864D01*
Y-73447D01*
X952819Y-73739D01*
G01X967262Y-94447D02*
X968791Y-95614D01*
X970537Y-95905D01*
X972065Y-95614D01*
X973376Y-94156D01*
X974249Y-92114D01*
Y-78406D01*
G01Y-80739D02*
X973376Y-79572D01*
X972065Y-78697D01*
X970537Y-78406D01*
X968791Y-78989D01*
X967699Y-80155D01*
X966825Y-82197D01*
X966389Y-84239D01*
X966607Y-85989D01*
X967481Y-88031D01*
X968791Y-89489D01*
X970537Y-90072D01*
X971847Y-89780D01*
X973376Y-88614D01*
X974249Y-87448D01*
G01X984107Y-90072D02*
Y-78406D01*
G01Y-81322D02*
X984981Y-79864D01*
X986291Y-78697D01*
X988037Y-78406D01*
X989565Y-78697D01*
X990876Y-79864D01*
X991531Y-81905D01*
Y-90072D01*
G01X1002044Y-82197D02*
X1009031D01*
X1008376Y-80155D01*
X1007284Y-78989D01*
X1005756Y-78406D01*
X1004227Y-78697D01*
X1002917Y-79572D01*
X1002044Y-81614D01*
X1001607Y-83364D01*
Y-85114D01*
X1002044Y-86864D01*
X1003136Y-88614D01*
X1004446Y-89780D01*
X1005974Y-90072D01*
X1007502Y-89489D01*
X1009031Y-87739D01*
G01X1019762Y-90072D02*
Y-78406D01*
G01Y-80739D02*
X1020854Y-79572D01*
X1021946Y-78697D01*
X1023474Y-78406D01*
X1024565Y-78697D01*
X1025876Y-79572D01*
G01X1066519Y-117572D02*
X1064772Y-118155D01*
X1063462Y-119614D01*
X1062589Y-121363D01*
X1061934Y-123697D01*
X1061716Y-126322D01*
X1061934Y-128947D01*
X1062589Y-131281D01*
X1063462Y-133031D01*
X1064772Y-134489D01*
X1066519Y-135072D01*
X1068265Y-134489D01*
X1069576Y-133031D01*
X1070449Y-131281D01*
X1071104Y-128947D01*
X1071322Y-126322D01*
X1071104Y-123697D01*
X1070449Y-121363D01*
X1069576Y-119614D01*
X1068265Y-118155D01*
X1066519Y-117572D01*
G01X1084019Y-135072D02*
X1085547Y-134780D01*
X1087294Y-133906D01*
X1088386Y-132448D01*
X1088822Y-130405D01*
X1088386Y-128364D01*
X1087076Y-126614D01*
X1085111Y-125739D01*
X1082927D01*
X1081617Y-125155D01*
X1080525Y-123697D01*
X1080089Y-121656D01*
X1080744Y-119614D01*
X1082272Y-118155D01*
X1084019Y-117572D01*
X1085765Y-118155D01*
X1087294Y-119614D01*
X1087949Y-121656D01*
X1087512Y-123697D01*
X1086421Y-125155D01*
X1085111Y-125739D01*
X1082927D01*
X1080962Y-126614D01*
X1079652Y-128364D01*
X1079216Y-130405D01*
X1079652Y-132448D01*
X1080744Y-133906D01*
X1082491Y-134780D01*
X1084019Y-135072D01*
G01X1097589Y-135655D02*
X1105449Y-117572D01*
G01X1119019D02*
X1117272Y-118155D01*
X1115962Y-119614D01*
X1115089Y-121363D01*
X1114434Y-123697D01*
X1114216Y-126322D01*
X1114434Y-128947D01*
X1115089Y-131281D01*
X1115962Y-133031D01*
X1117272Y-134489D01*
X1119019Y-135072D01*
X1120765Y-134489D01*
X1122076Y-133031D01*
X1122949Y-131281D01*
X1123604Y-128947D01*
X1123822Y-126322D01*
X1123604Y-123697D01*
X1122949Y-121363D01*
X1122076Y-119614D01*
X1120765Y-118155D01*
X1119019Y-117572D01*
G01X1136082Y-135072D02*
X1136519Y-131281D01*
X1137174Y-128072D01*
X1138047Y-125155D01*
X1139139Y-121947D01*
X1140886Y-117572D01*
X1132152D01*
G01X1150089Y-135655D02*
X1157949Y-117572D01*
G01X1167371Y-120489D02*
X1168681Y-118739D01*
X1170209Y-117864D01*
X1171956Y-117572D01*
X1174139Y-118155D01*
X1175667Y-119614D01*
X1176104Y-121363D01*
X1175886Y-123114D01*
X1175012Y-124572D01*
X1170646Y-127489D01*
X1168681Y-129530D01*
X1167371Y-132448D01*
X1166934Y-135072D01*
X1176104D01*
G01X1189019Y-117572D02*
X1187272Y-118155D01*
X1185962Y-119614D01*
X1185089Y-121363D01*
X1184434Y-123697D01*
X1184216Y-126322D01*
X1184434Y-128947D01*
X1185089Y-131281D01*
X1185962Y-133031D01*
X1187272Y-134489D01*
X1189019Y-135072D01*
X1190765Y-134489D01*
X1192076Y-133031D01*
X1192949Y-131281D01*
X1193604Y-128947D01*
X1193822Y-126322D01*
X1193604Y-123697D01*
X1192949Y-121363D01*
X1192076Y-119614D01*
X1190765Y-118155D01*
X1189019Y-117572D01*
G01X1206519Y-135072D02*
Y-117572D01*
X1203899Y-121072D01*
G01Y-135072D02*
X1209139D01*
G01X1223582D02*
X1224019Y-131281D01*
X1224674Y-128072D01*
X1225547Y-125155D01*
X1226639Y-121947D01*
X1228386Y-117572D01*
X1219652D01*
G01X1114216Y-90072D02*
Y-72572D01*
X1118582D01*
X1120329Y-73447D01*
X1121639Y-74614D01*
X1122731Y-76363D01*
X1123604Y-78406D01*
X1123822Y-81322D01*
X1123604Y-84239D01*
X1122731Y-86281D01*
X1121639Y-88031D01*
X1120329Y-89197D01*
X1118582Y-90072D01*
X1114216D01*
G01X1140449D02*
Y-78406D01*
G01Y-80447D02*
X1139576Y-79281D01*
X1138265Y-78697D01*
X1136737Y-78406D01*
X1135209Y-78989D01*
X1133899Y-80155D01*
X1133025Y-81905D01*
X1132589Y-84239D01*
X1133025Y-86572D01*
X1133899Y-88322D01*
X1135209Y-89489D01*
X1136737Y-90072D01*
X1138265Y-89780D01*
X1139576Y-88906D01*
X1140449Y-87739D01*
G01X1154019Y-72572D02*
Y-90072D01*
G01X1150962Y-78406D02*
X1157076D01*
G01X1168244Y-82197D02*
X1175231D01*
X1174576Y-80155D01*
X1173484Y-78989D01*
X1171956Y-78406D01*
X1170427Y-78697D01*
X1169117Y-79572D01*
X1168244Y-81614D01*
X1167807Y-83364D01*
Y-85114D01*
X1168244Y-86864D01*
X1169336Y-88614D01*
X1170646Y-89780D01*
X1172174Y-90072D01*
X1173702Y-89489D01*
X1175231Y-87739D01*
M02*
